# VersionTracker_F0TG3A03.xlsx — POEVT (spreadsheet-other)
| PO/EVT details |  |  |  |  |  |  |  |  |  |  |  |  |  |  |  |  |  |  |  |  |  |  |  |  |
| PO/EVT | 1A00 (2022WW24.3) | 1A01 (2022WW27.3) | 1A02 (2022WW28.5) | 1A03 (2022WW29.3) | 1A04 (2022WW314) | 1A05 (2022WW33.2) | 1A06 (2022WW33.4) | 1A07 (2022WW34.4) | 1A08 (2022WW37.4) | 1A09 (2022WW39.5) | 1A10 (2022WW43.1) | 1A11 (2022WW44.4) | 1A12 (2022WW47.5) | 1A13 (2022WW47.5) | 2A01 (2022WW49.4) | 2A02 (2023WW01.5) | 2A03 (2023WW05.4) | 2A04 (2023WW08.5) | 2A05 (2023WW12.6) | 2A06 (2023WW16.5) | 2A07 (2023WW19.4) | 3A01 (2023WW22.5) | 3A02 (2023WW23.2) | 3A03 (2023WW25.3) |
| BIOS Binary File Name | F0TG1A00.ROM | F0TG1A01.ROM | F0TG1A02.ROM | F0TG1A03.ROM | F0TG1A04.ROM | F0TG1A05.ROM | F0TG1A06.rom | F0TG1A07.rom | F0TG1A08.rom | F0TG1A09.rom | F0TG1A10.rom | F0TG1A11.BIN | F0TG1A12.BIN | F0TG1A13.BIN | F0TG2A01.BIN | F0TG2A02.BIN | F0TG2A03.BIN | F0TG2A04.BIN | F0TG2A05.BIN | F0TG2A06.BIN | F0TG2A07.BIN | F0TG3A01.BIN | F0TG3A02.BIN | F0TG3A03.BIN |
| Microcodes(See comment) | A0: 0x0A10004B B0: 0x0A100104 B1: 0x0A101009 | Genoa A0: 0x0A10004B Genoa A1: 0x0A100104 Genoa B0: 0x0A10100A Genoa B1: 0x0A101104 Bergamo A0: 0x0AA00004 | Genoa A0: 0x0A10004B Genoa A1: 0x0A100104 Genoa B0: 0x0A10100A Genoa B1: 0x0A101104 Bergamo A0: 0x0AA00004 | Genoa A0: 0x0A10004B Genoa A1: 0x0A100104 Genoa B0: 0x0A10100A Genoa B1: 0x0A101104 Bergamo A0: 0x0AA00004 | Genoa A0: 0x0A10004B Genoa A1: 0x0A100104 Genoa B0: 0x0A10100C Genoa B1: 0x0A101104 Bergamo A0: 0x0AA00004 | Genoa A0: 0x0A10004B Genoa A1: 0x0A100104 Genoa B0: 0x0A10100A Genoa B1: 0x0A101104 Bergamo A0: 0x0AA00004 | Genoa A0: 0x0A10004B Genoa A1: 0x0A100104 Genoa B0: 0x0A101010 Genoa B1: 0x0A101109 Bergamo A0: 0x0AA00004 | Genoa A0: 0x0A10004B Genoa A1: 0x0A100104 Genoa B0: 0x0A101010 Genoa B1: 0x0A101109 Bergamo A0: 0x0AA00004 | Genoa A0: 0x0A10004B Genoa A1: 0x0A100104 Genoa B0: 0x0A101010 Genoa B1: 0x0A101109 Bergamo A0: 0x0AA00006 Bergamo A1 :0x0AA00100 | Genoa A0: 0x0A10004B Genoa A1: 0x0A100104 Genoa B0: 0x0A101010 Genoa B1: 0x0A101109 Bergamo A0: 0x0AA00006 Bergamo A1 :0x0AA00100 | Genoa A0: 0x0A10004B Genoa A1: 0x0A100104 Genoa B0: 0x0A10101E Genoa B1: 0x0A10110D Bergamo A0: 0x0AA00007 Bergamo A1 :0x0AA00102 | Genoa A0: 0x0A10004B Genoa A1: 0x0A100104 Genoa B0: 0x0A10101E Genoa B1: 0x0A10110D Bergamo A0: 0x0AA00007 Bergamo A1 :0x0AA00102 | Genoa A0: 0x0A10004B Genoa A1: 0x0A100104 Genoa B0: 0x0A10101E Genoa B1: 0x0A10110E Bergamo A0: 0x0AA00007 Bergamo A1 :0x0AA00102 | Genoa B0: 0x0A101020 Genoa B1: 0x0A101111 Bergamo A0: 0x0AA00009 Bergamo A1 :0x0AA00105 | Genoa B0: 0x0A101020 Genoa B1: 0x0A101111 Bergamo A0: 0x0AA00009 Bergamo A1 :0x0AA00105 | Genoa B0: 0x0A101020 Genoa B1: 0x0A101111 Bergamo A0: 0x0AA00009 Bergamo A1 :0x0AA00105 | Genoa B0: 0x0A101020 Genoa B1: 0x0A101111 Bergamo A0: 0x0AA00009 Bergamo A1 :0x0AA00105 | Genoa B0: 0x0A101020 Genoa B1: 0x0A101116 Bergamo A0: 0x0AA00009 Bergamo A1 :0x0AA00107 Bergamo A2 :0x0AA00203 | Genoa B0: 0x0A101020 Genoa B1: 0x0A101116 Bergamo A0: 0x0AA00009 Bergamo A1 :0x0AA00107 Bergamo A2 :0x0AA00203 | Genoa B0: 0x0A101020 Genoa B1: 0x0A101116 Genoa B2: 0x0A101203 Bergamo A0: 0x0AA00009 Bergamo A1 :0x0AA00107 Bergamo A2 :0x0AA00205 | Genoa B0: 0x0A101020 Genoa B1: 0x0A101121 Genoa B2: 0x0A101207 Bergamo A0: 0x0AA00009 Bergamo A1 :0x0AA0010B Bergamo A2 :0x0AA00208 | Genoa B0: 0x0A101020 Genoa B1: 0x0A101135 Genoa B2: 0x0A101207 Bergamo A0: 0x0AA00009 Bergamo A1 :0x0AA0010B Bergamo A2 :0x0AA00208 | Genoa B0: 0x0A101020 Genoa B1: 0x0A101135 Genoa B2: 0x0A101207 Bergamo A0: 0x0AA00009 Bergamo A1 :0x0AA0010B Bergamo A2 :0x0AA00208 | Genoa B0: 0x0A101020 Genoa B1: 0x0A10113B Genoa B2: 0x0A10123B Bergamo A0: 0x0AA00009 Bergamo A1 :0x0AA00115 Bergamo A2 :0x0AA00211 |
| SMU version | 00.71.59.0 | 00.71.64.0 | 00.71.64.0 | 00.71.64.0 | 00.71.70.0 | 00.71.64.0 | 00.71.74.0 (A0) 04.71.74.0 (B0) 00.91.74.0 (Bergamo) | 00.71.74.0 (A0) 04.71.74.0 (B0) 00.91.74.0 (Bergamo) | 00.71.77.0 (A0) 04.71.77.0 (B0) 00.91.77.0 (Bergamo) | 00.71.77.0 (A0) 04.71.77.0 (B0) 00.91.77.0 (Bergamo) | 00.71.82.0 (A0) 04.71.82.0 (B0) 00.91.82.0 (Bergamo) | 00.71.82.0 (A0) 04.71.82.0 (B0) 00.91.82.0 (Bergamo) | 00.71.82.0 (A0) 04.71.82.0 (B0) 00.91.82.0 (Bergamo) | 04.71.88.0(B0) 00.91.88.0 (Bergamo) | 04.71.88.0(B0) 00.91.88.0 (Bergamo) | 04.71.91.0(B0) 00.91.91.0 (Bergamo) | 04.71.91.0(B0) 00.91.91.0 (Bergamo) | 04.71.95.0(B0) 00.91.95.0 (Bergamo) | 04.71.95.0(B0) 00.91.95.0 (Bergamo) | 04.71.98.0(B0) 00.91.98.0 (Bergamo) | 04.71.101.0(B0) 00.91.101.0 (Bergamo) | 04.71.101.0(B0) 00.91.101.0 (Bergamo) | 04.71.101.0(B0) 00.91.101.0 (Bergamo) | 04.71.111.0(B0) 00.91.111.0 (Bergamo) |
| PSP version | 00.29.00.43 | 00.29.00.4A | 00.29.00.4A | 00.29.00.4A | 00.29.00.53 | 00.29.00.4A | 00.29.00.5B | 00.29.00.5B | 00.29.00.5D | 00.29.00.5D | 00.29.00.71 | 00.29.00.71 | 00.29.00.71 | 00.29.00.78 | 00.29.00.78 | 00.29.00.7D | 00.29.00.7D | 00.29.00.80 | 00.29.00.80 | 00.29.00.84 | 00.29.00.88 | 00.29.00.88 | 00.29.00.88 | 00.29.00.90 |
| UEFI | 2.8 | 2.8 | 2.8 | 2.8 | 2.8 | 2.8 | 2.8 | 2.8 | 2.8 | 2.8 | 2.8 | 2.8 | 2.8 | 2.8 | 2.8 | 2.8 | 2.8 | 2.8 | 2.8 | 2.8 | 2.8 | 2.8 | 2.8 | 2.8 |
| PI | 1.7 | 1.7 | 1.7 | 1.7 | 1.7 | 1.7 | 1.7 | 1.7 | 1.7 | 1.7 | 1.7 | 1.7 | 1.7 | 1.7 | 1.7 | 1.7 | 1.7 | 1.7 | 1.7 | 1.7 | 1.7 | 1.7 | 1.7 | 1.7 |
| ABL | RABLRS00728013 | RABLRS00818012 | RABLRS00818012 | RABLRS00818012 | RABLRS00818012 | RABLRS00818012 | RABLRS10008014 | RABLRS10008014 | RABLRS10008012 | RABLRS10018012 | RABLRS10028012 | RABLRS10028012 | RABLRS10028012 | RABLRS10038016 | RABLRS10038016 | RABLRS10048012 | RABLRS10048012 | RABLRS10058013 | RABLRS10058013 | RABLRS10068011 | RABLRS10078013 | RABLRS10078013 | RABLRS10078013 | RABLRS10088011 |
| AMD GenoaPI Version | 0.0.8.0 | 0.0.8.1 | 0.0.8.1 | 0.0.8.1 | 0.0.9.0 | 0.0.8.1 | 1.0.0.0 | 1.0.0.0 | 1.0.0.1 | 1.0.0.1 | 1.0.0.2 | 1.0.0.2 | 1.0.0.2 | 1.0.0.3 | 1.0.0.3 | 1.0.0.4 | 1.0.0.4 | 1.0.0.5 | 1.0.0.5 | 1.0.0.6 | 1.0.0.7 | 1.0.0.7 | 1.0.0.7 | 1.0.0.8 |
| AMI label | 5.27_GenoaCrb_0ACQT010 | 5.27_GenoaCrb_0ACQT011 | 5.27_GenoaCrb_0ACQT011 | 5.27_GenoaCrb_0ACQT011 | 5.27_GenoaCrb_0ACQT012 | 5.27_GenoaCrb_0ACQT011 | 5.27_GenoaCrb_0ACQT013 | 5.27_GenoaCrb_0ACQT013 | 5.27_GenoaCrb_0ACQT014 | 5.27_GenoaCrb_0ACQT014 | 5.27_GenoaCrb_0ACQT015 | 5.27_GenoaCrb_0ACQT015 | 5.27_GenoaCrb_0ACQT015 | 5.27_GenoaCrb_0ACQT016 | 5.27_GenoaCrb_0ACQT016 | 5.27_GenoaCrb_0ACQT017 | 5.27_GenoaCrb_0ACQT017 | 5.27_GenoaCrb_0ACQT018 | 5.27_GenoaCrb_0ACQT018 | 5.27_GenoaCrb_0ACQT019 | 5.27_GenoaCrb_0ACQT020 | 5.27_GenoaCrb_0ACQT020 | 5.27_GenoaCrb_0ACQT020 | 5.27_GenoaCrb_0ACQT021 |
| MCA error thresh count | TBD | TBD | TBD | TBD | TBD | TBD | TBD | TBD | TBD | TBD | TBD | TBD | TBD | TBD | TBD | TBD | TBD | TBD | TBD | TBD | TBD | TBD | TBD | TBD |
| ECC error thresh count | TBD | TBD | TBD | TBD | TBD | TBD | TBD | TBD | TBD | TBD | TBD | TBD | TBD | TBD | 1 | 1 | 1 | 1 | 1 | 1 | 1 | 1 | 1 | 1 |
| TPM2.0 SHA256 PCR 0 | TBD | TBD | DA 6E 8A AA 36 95 C6 37 C1 99 FE 52 B2 D1 55 22 2D 2D 93 C1 28 2D E9 24 BC 4D 31 02 48 6D AE A2 | 64 09 1D 8F 1F 56 9F D3 98 D3 F6 97 51 B6 0A A9 30 D2 05 C9 C7 4C EF 81 28 D8 12 6B B7 52 2A 08 | 8C 2C 72 64 99 0E 03 4E 33 DE 0B 32 1D CD 43 64 19 EF 62 29 FB 22 04 0A FE 7E 81 30 FA F3 DB DC | C3 C7 BD 45 DB D1 88 0E DB 56 FE B3 F9 86 6C 85 D4 CB 46 29 D7 5C F9 AE 6A A1 6B 69 C1 17 52 71 | 71 3D 20 1A AF C3 1B B6 EB C8 00 3C DD D8 AD 75 D9 22 CD 2B 7D 3F EA 81 5F 6D EA E5 2C DB 8B CD | DE EF 87 65 B7 C1 C6 D5 79 59 92 7D C5 48 FC 77 D8 B5 CC C1 E1 24 DD 9C 76 2E B6 C8 99 3C EC EB | AF 31 B3 A3 D2 78 97 F6 C9 A1 8F 47 F9 22 DE 88 14 F4 1F 88 B9 4E 35 7F DF 3B 39 56 4B 59 72 E5 | 9A 07 9D 4C 9B 55 82 40 68 78 F9 FA 63 03 C9 F3 02 4E 45 27 7C 12 A9 FC 85 5D 10 51 EE C9 76 AE | 9B EA B6 87 51 6B 96 CF F0 36 4B CA F0 E0 88 3D 33 91 2D 0E 1A 85 75 1F 74 47 6F B9 4A F2 58 3D | 15 ED DF 58 10 AC 3C AE 8F 96 CD 0C 8B 6F 5C A0 DE 56 D0 A2 43 4F 3A 1A 77 4F D2 8C 98 FA 99 DF | 57 96 47 30 B8 D9 A5 1B 78 68 81 2B B5 5D 57 CE D0 F5 F9 DF 01 30 F4 76 27 3A CE FA C9 16 18 67 | 08 AB E4 27 CB 83 2E 4C CD ED 2C 3E 8A 45 29 7C 90 C7 95 AD A3 72 99 A2 92 FD 49 C3 96 2A 2F 4B | 53 D0 B6 75 9E A2 34 B0 59 88 E1 71 18 0D 49 8C 1C AF 6A 20 95 DC 4A 04 73 5C 67 D5 1A BB 90 A3 | D4 5F 05 20 D7 AC B6 A4 4B 67 69 0E 6C FC D9 33 52 BE FC 63 37 22 B0 F8 28 BF 05 F3 A2 6E 3D E0 | 56 E2 3B 47 59 90 D2 F9 16 19 A7 04 F6 B8 50 00 79 AE F3 0D B7 92 FD 35 DA 97 BC 32 C3 F5 D2 99 | D1 D1 57 91 A3 EE BC F3 13 7B FE D7 C7 15 E2 98 9A 20 C9 C4 BE AE 16 7A 9A B1 21 13 6B 85 FC 0A | 48 04 D3 58 70 F9 B3 63 77 62 86 F5 ED 17 BA E6 7F 48 5E DF 80 23 DA 0C C3 42 D7 6F 51 3C 99 86 | 8E AC 10 E5 8F 65 3A 83 5C 0F 3B 25 06 89 8B 0A 8F 20 05 20 56 F6 59 8F B7 29 61 59 89 8D B1 AD | ED D9 86 3E DD CE C7 CA 71 87 F2 B1 54 FC A8 8E C2 9F F3 3B AD D9 9A CC 38 1F 0F 2A B7 81 D6 7A | 45 27 29 D2 21 6E F4 D1 D8 7F DF 18 67 48 BA AF 05 E0 6C 6F CA A7 1A B0 8E E8 CE 19 C7 AE FB A1 | 11 45 4A 89 39 D1 9C 99 70 71 40 C1 D6 D4 8B 7B 2B 33 91 8B 9C 94 C4 95 13 18 66 A9 B7 AC CB E5 | 01 39 7C F6 A5 CA E5 07 42 A4 FA 2B 39 ED 28 80 83 AB E0 36 9F B4 35 21 E1 BA C2 D2 D5 72 F3 95 |
| Module Version | Label | Label | Label | Label |  |  |  |  |  |  |  |  |  |  |  |  |  |  |  |  |  |  |  |  |
| AmiCompatibilityPkg | AmiCompatibilityPkg_47 | AmiCompatibilityPkg_47 | AmiCompatibilityPkg_47 | AmiCompatibilityPkg_47 | AmiCompatibilityPkg_47 | AmiCompatibilityPkg_47 | AmiCompatibilityPkg_47 | AmiCompatibilityPkg_47 | AmiCompatibilityPkg_47 | AmiCompatibilityPkg_47 | AmiCompatibilityPkg_47 | AmiCompatibilityPkg_47 | AmiCompatibilityPkg_47 | AmiCompatibilityPkg_47 | AmiCompatibilityPkg_47 | AmiCompatibilityPkg_47 | AmiCompatibilityPkg_47 | AmiCompatibilityPkg_47 | AmiCompatibilityPkg_47 | AmiCompatibilityPkg_47 | AmiCompatibilityPkg_47 | AmiCompatibilityPkg_47 | AmiCompatibilityPkg_47 | AmiCompatibilityPkg_47 |
| Core | Core_5.27 | Core_5.27 | Core_5.27 | Core_5.27 | Core_5.27 | Core_5.27 | Core_5.27 | Core_5.27 | Core_5.27 | Core_5.27 | Core_5.27 | Core_5.27 | Core_5.27 | Core_5.27 | Core_5.27 | Core_5.27 | Core_5.27 | Core_5.27 | Core_5.27 | Core_5.27 | Core_5.27 | Core_5.27 | Core_5.27 | Core_5.27 |
| AmiPkg | AmiPkg_37 | AmiPkg_37 | AmiPkg_37 | AmiPkg_37 | AmiPkg_37 | AmiPkg_37 | AmiPkg_37 | AmiPkg_37 | AmiPkg_37 | AmiPkg_37 | AmiPkg_37 | AmiPkg_37 | AmiPkg_37 | AmiPkg_37 | AmiPkg_37 | AmiPkg_37 | AmiPkg_37 | AmiPkg_37 | AmiPkg_37 | AmiPkg_37 | AmiPkg_37 | AmiPkg_37 | AmiPkg_37 | AmiPkg_37 |
| AmiModulePkg | AmiModulePkg_65 | AmiModulePkg_65 | AmiModulePkg_65 | AmiModulePkg_65 | AmiModulePkg_65 | AmiModulePkg_65 | AmiModulePkg_65 | AmiModulePkg_65 | AmiModulePkg_65 | AmiModulePkg_65 | AmiModulePkg_65 | AmiModulePkg_65 | AmiModulePkg_65 | AmiModulePkg_65 | AmiModulePkg_65 | AmiModulePkg_65 | AmiModulePkg_65 | AmiModulePkg_65 | AmiModulePkg_65 | AmiModulePkg_65 | AmiModulePkg_65 | AmiModulePkg_65 | AmiModulePkg_65 | AmiModulePkg_65 |
| MdePkg | MdePkg_32 | MdePkg_32 | MdePkg_32 | MdePkg_32 | MdePkg_32 | MdePkg_32 | MdePkg_32 | MdePkg_32 | MdePkg_32 | MdePkg_32 | MdePkg_32 | MdePkg_32 | MdePkg_32 | MdePkg_32 | MdePkg_32 | MdePkg_32 | MdePkg_32 | MdePkg_32 | MdePkg_32 | MdePkg_32 | MdePkg_32 | MdePkg_32 | MdePkg_32 | MdePkg_32 |
| MdeModulePkg | MdeModulePkg_33 | MdeModulePkg_33 | MdeModulePkg_33 | MdeModulePkg_33 | MdeModulePkg_33 | MdeModulePkg_33 | MdeModulePkg_33 | MdeModulePkg_33 | MdeModulePkg_33 | MdeModulePkg_33 | MdeModulePkg_33 | MdeModulePkg_33 | MdeModulePkg_33 | MdeModulePkg_33 | MdeModulePkg_33 | MdeModulePkg_33 | MdeModulePkg_33 | MdeModulePkg_33 | MdeModulePkg_33 | MdeModulePkg_33 | MdeModulePkg_33 | MdeModulePkg_33 | MdeModulePkg_33 | MdeModulePkg_33 |
| IntelFrameworkPkg | IntelFrameworkPkg_11.1 | IntelFrameworkPkg_11.1 | IntelFrameworkPkg_11.1 | IntelFrameworkPkg_11.1 | IntelFrameworkPkg_11.1 | IntelFrameworkPkg_11.1 | IntelFrameworkPkg_11.1 | IntelFrameworkPkg_11.1 | IntelFrameworkPkg_11.1 | IntelFrameworkPkg_11.1 | IntelFrameworkPkg_11.1 | IntelFrameworkPkg_11.1 | IntelFrameworkPkg_11.1 | IntelFrameworkPkg_11.1 | IntelFrameworkPkg_11.1 | IntelFrameworkPkg_11.1 | IntelFrameworkPkg_11.1 | IntelFrameworkPkg_11.1 | IntelFrameworkPkg_11.1 | IntelFrameworkPkg_11.1 | IntelFrameworkPkg_11.1 | IntelFrameworkPkg_11.1 | IntelFrameworkPkg_11.1 | IntelFrameworkPkg_11.1 |
| IntelFrameworkModulePkg | IntelFrameworkModulePkg_13.1 | IntelFrameworkModulePkg_13.1 | IntelFrameworkModulePkg_13.1 | IntelFrameworkModulePkg_13.1 | IntelFrameworkModulePkg_13.1 | IntelFrameworkModulePkg_13.1 | IntelFrameworkModulePkg_13.1 | IntelFrameworkModulePkg_13.1 | IntelFrameworkModulePkg_13.1 | IntelFrameworkModulePkg_13.1 | IntelFrameworkModulePkg_13.1 | IntelFrameworkModulePkg_13.1 | IntelFrameworkModulePkg_13.1 | IntelFrameworkModulePkg_13.1 | IntelFrameworkModulePkg_13.1 | IntelFrameworkModulePkg_13.1 | IntelFrameworkModulePkg_13.1 | IntelFrameworkModulePkg_13.1 | IntelFrameworkModulePkg_13.1 | IntelFrameworkModulePkg_13.1 | IntelFrameworkModulePkg_13.1 | IntelFrameworkModulePkg_13.1 | IntelFrameworkModulePkg_13.1 | IntelFrameworkModulePkg_13.1 |
| AmiStatusCode | StatusCodeAmi_16 | StatusCodeAmi_16 | StatusCodeAmi_16 | StatusCodeAmi_16 | StatusCodeAmi_16 | StatusCodeAmi_16 | StatusCodeAmi_16 | StatusCodeAmi_16 | StatusCodeAmi_16 | StatusCodeAmi_16 | StatusCodeAmi_16 | StatusCodeAmi_16 | StatusCodeAmi_16 | StatusCodeAmi_16 | StatusCodeAmi_16 | StatusCodeAmi_16 | StatusCodeAmi_16 | StatusCodeAmi_16 | StatusCodeAmi_16 | StatusCodeAmi_16 | StatusCodeAmi_16 | StatusCodeAmi_16 | StatusCodeAmi_16 | StatusCodeAmi_16 |
| Bds | Bds_26 | Bds_26 | Bds_26 | Bds_26 | Bds_26 | Bds_26 | Bds_26 | Bds_26 | Bds_26 | Bds_26 | Bds_26 | Bds_26 | Bds_26 | Bds_26 | Bds_26 | Bds_26 | Bds_26 | Bds_26 | Bds_26 | Bds_26 | Bds_26 | Bds_26 | Bds_26 | Bds_26 |
| ConSplitter | ConSplitter_26 | ConSplitter_26 | ConSplitter_26 | ConSplitter_26 | ConSplitter_26 | ConSplitter_26 | ConSplitter_26 | ConSplitter_26 | ConSplitter_26 | ConSplitter_26 | ConSplitter_26 | ConSplitter_26 | ConSplitter_26 | ConSplitter_26 | ConSplitter_26 | ConSplitter_26 | ConSplitter_26 | ConSplitter_26 | ConSplitter_26 | ConSplitter_26 | ConSplitter_26 | ConSplitter_26 | ConSplitter_26 | ConSplitter_26 |
| Fid | Fid_10 | Fid_10 | Fid_10 | Fid_10 | Fid_10 | Fid_10 | Fid_10 | Fid_10 | Fid_10 | Fid_10 | Fid_10 | Fid_10 | Fid_10 | Fid_10 | Fid_10 | Fid_10 | Fid_10 | Fid_10 | Fid_10 | Fid_10 | Fid_10 | Fid_10 | Fid_10 | Fid_10 |
| FlashDriver | FlashDriver_08 | FlashDriver_08 | FlashDriver_08 | FlashDriver_08 | FlashDriver_08 | FlashDriver_08 | FlashDriver_08 | FlashDriver_08 | FlashDriver_08 | FlashDriver_08 | FlashDriver_08 | FlashDriver_08 | FlashDriver_08 | FlashDriver_08 | FlashDriver_08 | FlashDriver_08 | FlashDriver_08 | FlashDriver_08 | FlashDriver_08 | FlashDriver_08 | FlashDriver_08 | FlashDriver_08 | FlashDriver_08 | FlashDriver_08 |
| GraphicsConsole | GraphicsConsole_23 | GraphicsConsole_23 | GraphicsConsole_23 | GraphicsConsole_23 | GraphicsConsole_23 | GraphicsConsole_23 | GraphicsConsole_23 | GraphicsConsole_23 | GraphicsConsole_23 | GraphicsConsole_23 | GraphicsConsole_23 | GraphicsConsole_23 | GraphicsConsole_23 | GraphicsConsole_23 | GraphicsConsole_23 | GraphicsConsole_23 | GraphicsConsole_23 | GraphicsConsole_23 | GraphicsConsole_23 | GraphicsConsole_23 | GraphicsConsole_23 | GraphicsConsole_23 | GraphicsConsole_23 | GraphicsConsole_23 |
| NVRAM | NVRAM_27 | NVRAM_27 | NVRAM_27 | NVRAM_27 | NVRAM_27 | NVRAM_27 | NVRAM_27 | NVRAM_27 | NVRAM_27 | NVRAM_27 | NVRAM_27 | NVRAM_27 | NVRAM_27 | NVRAM_27 | NVRAM_27 | NVRAM_27 | NVRAM_27 | NVRAM_27 | NVRAM_27 | NVRAM_27 | NVRAM_27 | NVRAM_27 | NVRAM_27 | NVRAM_27 |
| AMISetupNVLock | AMISetupNVLock_13_1 | AMISetupNVLock_13_1 | AMISetupNVLock_13_1 | AMISetupNVLock_13_1 | AMISetupNVLock_13_1 | AMISetupNVLock_13_1 | AMISetupNVLock_13_1 | AMISetupNVLock_13_1 | AMISetupNVLock_13_1 | AMISetupNVLock_13_1 | AMISetupNVLock_13_1 | AMISetupNVLock_13_1 | AMISetupNVLock_13_1 | AMISetupNVLock_13_1 | AMISetupNVLock_13_1 | AMISetupNVLock_13_1 | AMISetupNVLock_13_1 | AMISetupNVLock_13_1 | AMISetupNVLock_13_1 | AMISetupNVLock_13_1 | AMISetupNVLock_13_1 | AMISetupNVLock_13_1 | AMISetupNVLock_13_1 | AMISetupNVLock_13_1 |
| RomLayout | RomLayout_13 | RomLayout_13 | RomLayout_13 | RomLayout_13 | RomLayout_13 | RomLayout_13 | RomLayout_13 | RomLayout_13 | RomLayout_13 | RomLayout_13 | RomLayout_13 | RomLayout_13 | RomLayout_13 | RomLayout_13 | RomLayout_13 | RomLayout_13 | RomLayout_13 | RomLayout_13 | RomLayout_13 | RomLayout_13 | RomLayout_13 | RomLayout_13 | RomLayout_13 | RomLayout_13 |
| DataHub | DataHub_03 | DataHub_03 | DataHub_03 | DataHub_03 | DataHub_03 | DataHub_03 | DataHub_03 | DataHub_03 | DataHub_03 | DataHub_03 | DataHub_03 | DataHub_03 | DataHub_03 | DataHub_03 | DataHub_03 | DataHub_03 | DataHub_03 | DataHub_03 | DataHub_03 | DataHub_03 | DataHub_03 | DataHub_03 | DataHub_03 | DataHub_03 |
| Capsule | Capsule_15 | Capsule_15 | Capsule_15 | Capsule_15 | Capsule_15 | Capsule_15 | Capsule_15 | Capsule_15 | Capsule_15 | Capsule_15 | Capsule_15 | Capsule_15 | Capsule_15 | Capsule_15 | Capsule_15 | Capsule_15 | Capsule_15 | Capsule_15 | Capsule_15 | Capsule_15 | Capsule_15 | Capsule_15 | Capsule_15 | Capsule_15 |
| Foundation | Foundation_30 | Foundation_30 | Foundation_30 | Foundation_30 | Foundation_30 | Foundation_30 | Foundation_30 | Foundation_30 | Foundation_30 | Foundation_30 | Foundation_30 | Foundation_30 | Foundation_30 | Foundation_30 | Foundation_30 | Foundation_30 | Foundation_30 | Foundation_30 | Foundation_30 | Foundation_30 | Foundation_30 | Foundation_30 | Foundation_30 | Foundation_30 |
| DevicePath | DevicePath_05 | DevicePath_05 | DevicePath_05 | DevicePath_05 | DevicePath_05 | DevicePath_05 | DevicePath_05 | DevicePath_05 | DevicePath_05 | DevicePath_05 | DevicePath_05 | DevicePath_05 | DevicePath_05 | DevicePath_05 | DevicePath_05 | DevicePath_05 | DevicePath_05 | DevicePath_05 | DevicePath_05 | DevicePath_05 | DevicePath_05 | DevicePath_05 | DevicePath_05 | DevicePath_05 |
| Disk | Disk_21 | Disk_21 | Disk_21 | Disk_21 | Disk_21 | Disk_21 | Disk_21 | Disk_21 | Disk_21 | Disk_21 | Disk_21 | Disk_21 | Disk_21 | Disk_21 | Disk_21 | Disk_21 | Disk_21 | Disk_21 | Disk_21 | Disk_21 | Disk_21 | Disk_21 | Disk_21 | Disk_21 |
| RamDisk | RamDisk_06 | RamDisk_06 | RamDisk_06 | RamDisk_06 | RamDisk_06 | RamDisk_06 | RamDisk_06 | RamDisk_06 | RamDisk_06 | RamDisk_06 | RamDisk_06 | RamDisk_06 | RamDisk_06 | RamDisk_06 | RamDisk_06 | RamDisk_06 | RamDisk_06 | RamDisk_06 | RamDisk_06 | RamDisk_06 | RamDisk_06 | RamDisk_06 | RamDisk_06 | RamDisk_06 |
| Ebc | Ebc_09 | Ebc_09 | Ebc_09 | Ebc_09 | Ebc_09 | Ebc_09 | Ebc_09 | Ebc_09 | Ebc_09 | Ebc_09 | Ebc_09 | Ebc_09 | Ebc_09 | Ebc_09 | Ebc_09 | Ebc_09 | Ebc_09 | Ebc_09 | Ebc_09 | Ebc_09 | Ebc_09 | Ebc_09 | Ebc_09 | Ebc_09 |
| HiiDatabase | HiiDatabase_22 | HiiDatabase_22 | HiiDatabase_22 | HiiDatabase_22 | HiiDatabase_22 | HiiDatabase_22 | HiiDatabase_22 | HiiDatabase_22 | HiiDatabase_22 | HiiDatabase_22 | HiiDatabase_22 | HiiDatabase_22 | HiiDatabase_22 | HiiDatabase_22 | HiiDatabase_22 | HiiDatabase_22 | HiiDatabase_22 | HiiDatabase_22 | HiiDatabase_22 | HiiDatabase_22 | HiiDatabase_22 | HiiDatabase_22 | HiiDatabase_22 | HiiDatabase_22 |
| Pcd | PCD_11 | PCD_11 | PCD_11 | PCD_11 | PCD_11 | PCD_11 | PCD_11 | PCD_11 | PCD_11 | PCD_11 | PCD_11 | PCD_11 | PCD_11 | PCD_11 | PCD_11 | PCD_11 | PCD_11 | PCD_11 | PCD_11 | PCD_11 | PCD_11 | PCD_11 | PCD_11 | PCD_11 |
| SecurityStub | SecurityStub_05 | SecurityStub_05 | SecurityStub_05 | SecurityStub_05 | SecurityStub_05 | SecurityStub_05 | SecurityStub_05 | SecurityStub_05 | SecurityStub_05 | SecurityStub_05 | SecurityStub_05 | SecurityStub_05 | SecurityStub_05 | SecurityStub_05 | SecurityStub_05 | SecurityStub_05 | SecurityStub_05 | SecurityStub_05 | SecurityStub_05 | SecurityStub_05 | SecurityStub_05 | SecurityStub_05 | SecurityStub_05 | SecurityStub_05 |
| Timestamp | Timestamp_03 | Timestamp_03 | Timestamp_03 | Timestamp_03 | Timestamp_03 | Timestamp_03 | Timestamp_03 | Timestamp_03 | Timestamp_03 | Timestamp_03 | Timestamp_03 | Timestamp_03 | Timestamp_03 | Timestamp_03 | Timestamp_03 | Timestamp_03 | Timestamp_03 | Timestamp_03 | Timestamp_03 | Timestamp_03 | Timestamp_03 | Timestamp_03 | Timestamp_03 | Timestamp_03 |
| CpuIo | CpuIo_05 | CpuIo_05 | CpuIo_05 | CpuIo_05 | CpuIo_05 | CpuIo_05 | CpuIo_05 | CpuIo_05 | CpuIo_05 | CpuIo_05 | CpuIo_05 | CpuIo_05 | CpuIo_05 | CpuIo_05 | CpuIo_05 | CpuIo_05 | CpuIo_05 | CpuIo_05 | CpuIo_05 | CpuIo_05 | CpuIo_05 | CpuIo_05 | CpuIo_05 | CpuIo_05 |
| SmmLockBox | SmmLockBox_10 | SmmLockBox_10 | SmmLockBox_10 | SmmLockBox_10 | SmmLockBox_10 | SmmLockBox_10 | SmmLockBox_10 | SmmLockBox_10 | SmmLockBox_10 | SmmLockBox_10 | SmmLockBox_10 | SmmLockBox_10 | SmmLockBox_10 | SmmLockBox_10 | SmmLockBox_10 | SmmLockBox_10 | SmmLockBox_10 | SmmLockBox_10 | SmmLockBox_10 | SmmLockBox_10 | SmmLockBox_10 | SmmLockBox_10 | SmmLockBox_10 | SmmLockBox_10 |
| Flash | Flash_35 | Flash_35 | Flash_35 | Flash_35 | Flash_35 | Flash_35 | Flash_35 | Flash_35 | Flash_35 | Flash_35 | Flash_35 | Flash_35 | Flash_35 | Flash_35 | Flash_35 | Flash_35 | Flash_35 | Flash_35 | Flash_35 | Flash_35 | Flash_35 | Flash_35 | Flash_35 | Flash_35 |
| SpiAmdFchRs | SpiAmdFchRs_04 | SpiAmdFchRs_05 | SpiAmdFchRs_05 | SpiAmdFchRs_05 | SpiAmdFchRs_05 | SpiAmdFchRs_05 | SpiAmdFchRs_05 | SpiAmdFchRs_05 | SpiAmdFchRs_05 | SpiAmdFchRs_05 | SpiAmdFchRs_06 | SpiAmdFchRs_06 | SpiAmdFchRs_06 | SpiAmdFchRs_06 | SpiAmdFchRs_06 | SpiAmdFchRs_07 | SpiAmdFchRs_07 | SpiAmdFchRs_07 | SpiAmdFchRs_07 | SpiAmdFchRs_07 | SpiAmdFchRs_07 | SpiAmdFchRs_07 | SpiAmdFchRs_07 | SpiAmdFchRs_07 |
| AmiCpuPkg | AmiCpuPkg_07 | AmiCpuPkg_08 | AmiCpuPkg_08 | AmiCpuPkg_08 | AmiCpuPkg_08 | AmiCpuPkg_08 | AmiCpuPkg_09 | AmiCpuPkg_09 | AmiCpuPkg_09 | AmiCpuPkg_09 | AmiCpuPkg_09 | AmiCpuPkg_09 | AmiCpuPkg_09 | AmiCpuPkg_10 | AmiCpuPkg_10 | AmiCpuPkg_10 | AmiCpuPkg_10 | AmiCpuPkg_10 | AmiCpuPkg_10 | AmiCpuPkg_11 | AmiCpuPkg_12 | AmiCpuPkg_12 | AmiCpuPkg_12 | AmiCpuPkg_13 |
| AmiChipsetPkg | AmiChipsetPkg_15 | AmiChipsetPkg_15 | AmiChipsetPkg_15 | AmiChipsetPkg_15 | AmiChipsetPkg_15 | AmiChipsetPkg_15 | AmiChipsetPkg_15 | AmiChipsetPkg_15 | AmiChipsetPkg_15 | AmiChipsetPkg_15 | AmiChipsetPkg_15 | AmiChipsetPkg_15 | AmiChipsetPkg_15 | AmiChipsetPkg_15 | AmiChipsetPkg_15 | AmiChipsetPkg_15 | AmiChipsetPkg_15 | AmiChipsetPkg_15 | AmiChipsetPkg_15 | AmiChipsetPkg_15 | AmiChipsetPkg_15 | AmiChipsetPkg_15 | AmiChipsetPkg_15 | AmiChipsetPkg_15 |
| NB | NB_12 | NB_13 | NB_13 | NB_13 | NB_13 | NB_13 | NB_14 | NB_14 | NB_15 | NB_15 | NB_16 | NB_16 | NB_16 | NB_17 | NB_17 | NB_17 | NB_17 | NB_17 | NB_17 | NB_18 | NB_18 | NB_18 | NB_18 | NB_19 |
| SB | SB_09 | SB_10 | SB_10 | SB_10 | SB_11 | SB_10 | SB_12 | SB_12 | SB_13 | SB_13 | SB_14 | SB_14 | SB_14 | SB_14 | SB_14 | SB_14 | SB_14 | SB_15 | SB_15 | SB_15 | SB_15 | SB_15 | SB_15 | SB_15 |
| AmiChipsetModulePkg | AmiChipsetModulePkg_01 | AmiChipsetModulePkg_01 | AmiChipsetModulePkg_01 | AmiChipsetModulePkg_01 | AmiChipsetModulePkg_01 | AmiChipsetModulePkg_01 | AmiChipsetModulePkg_01 | AmiChipsetModulePkg_01 | AmiChipsetModulePkg_02 | AmiChipsetModulePkg_02 | AmiChipsetModulePkg_02 | AmiChipsetModulePkg_02 | AmiChipsetModulePkg_02 | AmiChipsetModulePkg_02 | AmiChipsetModulePkg_02 | AmiChipsetModulePkg_02 | AmiChipsetModulePkg_02 | AmiChipsetModulePkg_02 | AmiChipsetModulePkg_02 | AmiChipsetModulePkg_02 | AmiChipsetModulePkg_02 | AmiChipsetModulePkg_02 | AmiChipsetModulePkg_02 | AmiChipsetModulePkg_02 |
| AHCI | AHCI_30 | AHCI_30 | AHCI_30 | AHCI_30 | AHCI_30 | AHCI_30 | AHCI_30 | AHCI_30 | AHCI_30 | AHCI_30 | AHCI_30 | AHCI_30 | AHCI_30 | AHCI_30 | AHCI_30 | AHCI_31 | AHCI_31 | AHCI_31 | AHCI_31 | AHCI_31 | AHCI_31 | AHCI_31 | AHCI_31 | AHCI_31 |
| TSE Binary | AMITSE_2_22_1285 | AMITSE_2_22_1285 | AMITSE_2_22_1285 | AMITSE_2_22_1285 | AMITSE_2_22_1285 | AMITSE_2_22_1285 | AMITSE_2_22_1285 | AMITSE_2_22_1285 | AMITSE_2_22_1285 | AMITSE_2_22_1285 | AMITSE_2_22_1285 | AMITSE_2_22_1285 | AMITSE_2_22_1285 | AMITSE_2_22_1285 | AMITSE_2_22_1285 | AMITSE_2_22_1285 | AMITSE_2_22_1285 | AMITSE_2_22_1285 | AMITSE_2_22_1285 | AMITSE_2_22_1285 | AMITSE_2_22_1285 | AMITSE_2_22_1285 | AMITSE_2_22_1285 | AMITSE_2_22_1285 |
| TSE Sources | TSESources_2_22_1285 | TSESources_2_22_1285 | TSESources_2_22_1285 | TSESources_2_22_1285 | TSESources_2_22_1285 | TSESources_2_22_1285 | TSESources_2_22_1285 | TSESources_2_22_1285 | TSESources_2_22_1285 | TSESources_2_22_1285 | TSESources_2_22_1285 | TSESources_2_22_1285 | TSESources_2_22_1285 | TSESources_2_22_1285 | TSESources_2_22_1285 | TSESources_2_22_1285 | TSESources_2_22_1285 | TSESources_2_22_1285 | TSESources_2_22_1285 | TSESources_2_22_1285 | TSESources_2_22_1285 | TSESources_2_22_1285 | TSESources_2_22_1285 | TSESources_2_22_1285 |
| AgesaModulePkg | AgesaModulePkg_11 | AgesaModulePkg_12 | AgesaModulePkg_12 | AgesaModulePkg_12 | AgesaModulePkg_13 | AgesaModulePkg_12 | AgesaModulePkg_14 | AgesaModulePkg_14 | AgesaModulePkg_15 | AgesaModulePkg_15 | AgesaModulePkg_16 | AgesaModulePkg_16 | AgesaModulePkg_16 | AgesaModulePkg_17 | AgesaModulePkg_17 | AgesaModulePkg_18 | AgesaModulePkg_18 | AgesaModulePkg_19 | AgesaModulePkg_19 | AgesaModulePkg_20 | AgesaModulePkg_21 | AgesaModulePkg_21 | AgesaModulePkg_21 | AgesaModulePkg_23 |
| AgesaPkg | AgesaPkg_10 | AgesaPkg_11 | AgesaPkg_11 | AgesaPkg_11 | AgesaPkg_12 | AgesaPkg_11 | AgesaPkg_13 | AgesaPkg_13 | AgesaPkg_14 | AgesaPkg_14 | AgesaPkg_15 | AgesaPkg_15 | AgesaPkg_15 | AgesaPkg_16 | AgesaPkg_16 | AgesaPkg_17 | AgesaPkg_17 | AgesaPkg_18 | AgesaPkg_18 | AgesaPkg_19 | AgesaPkg_20 | AgesaPkg_20 | AgesaPkg_20 | AgesaPkg_21 |
| AmdCbsPkg | AmdCbsPkg_10 | AmdCbsPkg_11 | AmdCbsPkg_11 | AmdCbsPkg_11 | AmdCbsPkg_12 | AmdCbsPkg_11 | AmdCbsPkg_13 | AmdCbsPkg_13 | AmdCbsPkg_14 | AmdCbsPkg_14 | AmdCbsPkg_15 | AmdCbsPkg_15 | AmdCbsPkg_15 | AmdCbsPkg_16 | AmdCbsPkg_16 | AmdCbsPkg_17 | AmdCbsPkg_17 | AmdCbsPkg_18 | AmdCbsPkg_18 | AmdCbsPkg_19 | AmdCbsPkg_20 | AmdCbsPkg_20 | AmdCbsPkg_20 | AmdCbsPkg_21 |
| AmdCpmPkg | AmdCpmPkg_10 | AmdCpmPkg_11 | AmdCpmPkg_11 | AmdCpmPkg_11 | AmdCpmPkg_12 | AmdCpmPkg_11 | AmdCpmPkg_13 | AmdCpmPkg_13 | AmdCpmPkg_14 | AmdCpmPkg_14 | AmdCpmPkg_15 | AmdCpmPkg_15 | AmdCpmPkg_15 | AmdCpmPkg_16 | AmdCpmPkg_16 | AmdCpmPkg_17 | AmdCpmPkg_17 | AmdCpmPkg_18 | AmdCpmPkg_18 | AmdCpmPkg_19 | AmdCpmPkg_20 | AmdCpmPkg_20 | AmdCpmPkg_20 | AmdCpmPkg_21 |
| UefiCpuPkg | GenoaUefiCpuPkg_04 | GenoaUefiCpuPkg_05 | GenoaUefiCpuPkg_05 | GenoaUefiCpuPkg_05 | GenoaUefiCpuPkg_05 | GenoaUefiCpuPkg_05 | GenoaUefiCpuPkg_05 | GenoaUefiCpuPkg_05 | GenoaUefiCpuPkg_05 | GenoaUefiCpuPkg_05 | GenoaUefiCpuPkg_05 | GenoaUefiCpuPkg_05 | GenoaUefiCpuPkg_05 | GenoaUefiCpuPkg_06 | GenoaUefiCpuPkg_06 | GenoaUefiCpuPkg_06 | GenoaUefiCpuPkg_06 | GenoaUefiCpuPkg_07 | GenoaUefiCpuPkg_07 | GenoaUefiCpuPkg_07 | GenoaUefiCpuPkg_07 | GenoaUefiCpuPkg_07 | GenoaUefiCpuPkg_07 | GenoaUefiCpuPkg_07 |
| Setup | Setup_17.1 | Setup_17.1 | Setup_17.1 | Setup_17.1 | Setup_17.1 | Setup_17.1 | Setup_17.1 | Setup_17.1 | Setup_17.1 | Setup_17.1 | Setup_17.1 | Setup_17.1 | Setup_17.1 | Setup_17.1 | Setup_17.1 | Setup_17.1 | Setup_17.1 | Setup_17.1 | Setup_17.1 | Setup_17.1 | Setup_17.1 | Setup_17.1 | Setup_17.1 | Setup_17.1 |
| AmiCryptoPkg | AmiCryptoPkg_48 | AmiCryptoPkg_48 | AmiCryptoPkg_48 | AmiCryptoPkg_48 | AmiCryptoPkg_48 | AmiCryptoPkg_48 | AmiCryptoPkg_48 | AmiCryptoPkg_48 | AmiCryptoPkg_48 | AmiCryptoPkg_48 | AmiCryptoPkg_48 | AmiCryptoPkg_48 | AmiCryptoPkg_48 | AmiCryptoPkg_48 | AmiCryptoPkg_48 | AmiCryptoPkg_48 | AmiCryptoPkg_48 | AmiCryptoPkg_48 | AmiCryptoPkg_48 | AmiCryptoPkg_48 | AmiCryptoPkg_48 | AmiCryptoPkg_48 | AmiCryptoPkg_48 | AmiCryptoPkg_48 |
| AmiGpnvErrorLoggingPkg | AmiGpnvErrorLoggingPkg_13 | AmiGpnvErrorLoggingPkg_13 | AmiGpnvErrorLoggingPkg_13 | AmiGpnvErrorLoggingPkg_13 | AmiGpnvErrorLoggingPkg_13 | AmiGpnvErrorLoggingPkg_13 | AmiGpnvErrorLoggingPkg_13 | AmiGpnvErrorLoggingPkg_13 | AmiGpnvErrorLoggingPkg_13 | AmiGpnvErrorLoggingPkg_13 | AmiGpnvErrorLoggingPkg_13 | AmiGpnvErrorLoggingPkg_13 | AmiGpnvErrorLoggingPkg_13 | AmiGpnvErrorLoggingPkg_13 | AmiGpnvErrorLoggingPkg_13 | AmiGpnvErrorLoggingPkg_13 | AmiGpnvErrorLoggingPkg_13 | AmiGpnvErrorLoggingPkg_13 | AmiGpnvErrorLoggingPkg_13 | AmiGpnvErrorLoggingPkg_13 | AmiGpnvErrorLoggingPkg_13 | AmiGpnvErrorLoggingPkg_13 | AmiGpnvErrorLoggingPkg_13 | AmiGpnvErrorLoggingPkg_13 |
| AmiHstiPkg | AmiHstiPkg_06 | AmiHstiPkg_06 | AmiHstiPkg_06 | AmiHstiPkg_06 | AmiHstiPkg_06 | AmiHstiPkg_06 | AmiHstiPkg_06 | AmiHstiPkg_06 | AmiHstiPkg_06 | AmiHstiPkg_06 | AmiHstiPkg_06 | AmiHstiPkg_06 | AmiHstiPkg_06 | AmiHstiPkg_06 | AmiHstiPkg_06 | AmiHstiPkg_06 | AmiHstiPkg_06 | AmiHstiPkg_06 | AmiHstiPkg_06 | AmiHstiPkg_06 | AmiHstiPkg_06 | AmiHstiPkg_06 | AmiHstiPkg_06 | AmiHstiPkg_06 |
| AmiIpmi2Pkg | AmiIpmi2Pkg_13 | AmiIpmi2Pkg_13 | AmiIpmi2Pkg_13 | AmiIpmi2Pkg_13 | AmiIpmi2Pkg_13 | AmiIpmi2Pkg_13 | AmiIpmi2Pkg_13 | AmiIpmi2Pkg_13 | AmiIpmi2Pkg_13 | AmiIpmi2Pkg_13 | AmiIpmi2Pkg_13 | AmiIpmi2Pkg_13 | AmiIpmi2Pkg_13 | AmiIpmi2Pkg_13 | AmiIpmi2Pkg_13 | AmiIpmi2Pkg_13 | AmiIpmi2Pkg_13 | AmiIpmi2Pkg_13 | AmiIpmi2Pkg_13 | AmiIpmi2Pkg_13 | AmiIpmi2Pkg_13 | AmiIpmi2Pkg_13 | AmiIpmi2Pkg_13 | AmiIpmi2Pkg_13 |
| Ipmi2 | Ipmi2_13 | Ipmi2_13 | Ipmi2_13 | Ipmi2_13 | Ipmi2_13 | Ipmi2_13 | Ipmi2_13 | Ipmi2_13 | Ipmi2_13 | Ipmi2_13 | Ipmi2_13 | Ipmi2_13 | Ipmi2_13 | Ipmi2_13 | Ipmi2_13 | Ipmi2_13 | Ipmi2_13 | Ipmi2_13 | Ipmi2_13 | Ipmi2_13 | Ipmi2_13 | Ipmi2_13 | Ipmi2_13 | Ipmi2_13 |
| ACPI | ACPI_25 | ACPI_25 | ACPI_25 | ACPI_25 | ACPI_26 | ACPI_25 | ACPI_26 | ACPI_26 | ACPI_26 | ACPI_26 | ACPI_26 | ACPI_26 | ACPI_26 | ACPI_26 | ACPI_26 | ACPI_26 | ACPI_26 | ACPI_26 | ACPI_26 | ACPI_26 | ACPI_26 | ACPI_26 | ACPI_26 | ACPI_26 |
| AmiGopPolicy | AmiGopPolicy_14.1 | AmiGopPolicy_14.1 | AmiGopPolicy_14.1 | AmiGopPolicy_14.1 | AmiGopPolicy_14.1 | AmiGopPolicy_14.1 | AmiGopPolicy_14.1 | AmiGopPolicy_14.1 | AmiGopPolicy_14.1 | AmiGopPolicy_14.1 | AmiGopPolicy_14.1 | AmiGopPolicy_14.1 | AmiGopPolicy_14.1 | AmiGopPolicy_14.1 | AmiGopPolicy_14.1 | AmiGopPolicy_14.1 | AmiGopPolicy_14.1 | AmiGopPolicy_14.1 | AmiGopPolicy_14.1 | AmiGopPolicy_14.1 | AmiGopPolicy_14.1 | AmiGopPolicy_14.1 | AmiGopPolicy_14.1 | AmiGopPolicy_14.1 |
| AMI Rom Concatenate | AmiRomConcat_02 | AmiRomConcat_02 | AmiRomConcat_02 | AmiRomConcat_02 | AmiRomConcat_02 | AmiRomConcat_02 | AmiRomConcat_02 | AmiRomConcat_02 | AmiRomConcat_02 | AmiRomConcat_02 | AmiRomConcat_02 | AmiRomConcat_02 | AmiRomConcat_02 | AmiRomConcat_02 | AmiRomConcat_02 | AmiRomConcat_02 | AmiRomConcat_02 | AmiRomConcat_02 | AmiRomConcat_02 | AmiRomConcat_02 | AmiRomConcat_02 | AmiRomConcat_02 | AmiRomConcat_02 | AmiRomConcat_02 |
| DebugPortTables | DebugPortTables_03 | DebugPortTables_03 | DebugPortTables_03 | DebugPortTables_03 | DebugPortTables_03 | DebugPortTables_03 | DebugPortTables_03 | DebugPortTables_03 | DebugPortTables_03 | DebugPortTables_03 | DebugPortTables_03 | DebugPortTables_03 | DebugPortTables_03 | DebugPortTables_03 | DebugPortTables_03 | DebugPortTables_03 | DebugPortTables_03 | DebugPortTables_03 | DebugPortTables_03 | DebugPortTables_03 | DebugPortTables_03 | DebugPortTables_03 | DebugPortTables_03 | DebugPortTables_03 |
| EarlyConsoleOut | EarlyConsoleOut_07 | EarlyConsoleOut_07 | EarlyConsoleOut_07 | EarlyConsoleOut_07 | EarlyConsoleOut_07 | EarlyConsoleOut_07 | EarlyConsoleOut_07 | EarlyConsoleOut_07 | EarlyConsoleOut_07 | EarlyConsoleOut_07 | EarlyConsoleOut_07 | EarlyConsoleOut_07 | EarlyConsoleOut_07 | EarlyConsoleOut_07 | EarlyConsoleOut_07 | EarlyConsoleOut_07 | EarlyConsoleOut_07 | EarlyConsoleOut_07 | EarlyConsoleOut_07 | EarlyConsoleOut_07 | EarlyConsoleOut_07 | EarlyConsoleOut_07 | EarlyConsoleOut_07 | EarlyConsoleOut_07 |
| EfiOsBootOptionNames | EfiOsBootOptionNames_19 | EfiOsBootOptionNames_19 | EfiOsBootOptionNames_19 | EfiOsBootOptionNames_19 | EfiOsBootOptionNames_19 | EfiOsBootOptionNames_19 | EfiOsBootOptionNames_19 | EfiOsBootOptionNames_19 | EfiOsBootOptionNames_19 | EfiOsBootOptionNames_19 | EfiOsBootOptionNames_19 | EfiOsBootOptionNames_19 | EfiOsBootOptionNames_19 | EfiOsBootOptionNames_19 | EfiOsBootOptionNames_19 | EfiOsBootOptionNames_19 | EfiOsBootOptionNames_19 | EfiOsBootOptionNames_19 | EfiOsBootOptionNames_19 | EfiOsBootOptionNames_19 | EfiOsBootOptionNames_19 | EfiOsBootOptionNames_19 | EfiOsBootOptionNames_19 | EfiOsBootOptionNames_19 |
| GenericSio | GenericSio_17.1 | GenericSio_17.1 | GenericSio_17.1 | GenericSio_17.1 | GenericSio_17.1 | GenericSio_17.1 | GenericSio_17.1 | GenericSio_17.1 | GenericSio_17.1 | GenericSio_17.1 | GenericSio_17.1 | GenericSio_17.1 | GenericSio_17.1 | GenericSio_17.1 | GenericSio_17.1 | GenericSio_17.1 | GenericSio_17.1 | GenericSio_17.1 | GenericSio_17.1 | GenericSio_17.1 | GenericSio_17.1 | GenericSio_17.1 | GenericSio_17.1 | GenericSio_17.1 |
| HardwareSignatureManagement | HardwareSignatureManagement_13 | HardwareSignatureManagement_13 | HardwareSignatureManagement_13 | HardwareSignatureManagement_13 | HardwareSignatureManagement_13 | HardwareSignatureManagement_13 | HardwareSignatureManagement_13 | HardwareSignatureManagement_13 | HardwareSignatureManagement_13 | HardwareSignatureManagement_13 | HardwareSignatureManagement_13 | HardwareSignatureManagement_13 | HardwareSignatureManagement_13 | HardwareSignatureManagement_13 | HardwareSignatureManagement_13 | HardwareSignatureManagement_13 | HardwareSignatureManagement_13 | HardwareSignatureManagement_13 | HardwareSignatureManagement_13 | HardwareSignatureManagement_13 | HardwareSignatureManagement_13 | HardwareSignatureManagement_13 | HardwareSignatureManagement_13 | HardwareSignatureManagement_13 |
| Legacy Serial Redirection | LegacySreDir_16 | LegacySreDir_16 | LegacySreDir_16 | LegacySreDir_16 | LegacySreDir_16 | LegacySreDir_16 | LegacySreDir_16 | LegacySreDir_16 | LegacySreDir_16 | LegacySreDir_16 | LegacySreDir_16 | LegacySreDir_16 | LegacySreDir_16 | LegacySreDir_16 | LegacySreDir_16 | LegacySreDir_16.1 | LegacySreDir_16.1 | LegacySreDir_16.1 | LegacySreDir_16.1 | LegacySreDir_16.1 | LegacySreDir_16.1 | LegacySreDir_16.1 | LegacySreDir_16.1 | LegacySreDir_16.1 |
| NetBootHotKey | NetBootHotKey_04 | NetBootHotKey_04 | NetBootHotKey_04 | NetBootHotKey_04 | NetBootHotKey_04 | NetBootHotKey_04 | NetBootHotKey_04 | NetBootHotKey_04 | NetBootHotKey_04 | NetBootHotKey_04 | NetBootHotKey_04 | NetBootHotKey_04 | NetBootHotKey_04 | NetBootHotKey_04 | NetBootHotKey_04 | NetBootHotKey_04 | NetBootHotKey_04 | NetBootHotKey_04 | NetBootHotKey_04 | NetBootHotKey_04 | NetBootHotKey_04 | NetBootHotKey_04 | NetBootHotKey_04 | NetBootHotKey_04 |
| OemActivation | OemActivation_18 | OemActivation_18 | OemActivation_18 | OemActivation_18 | OemActivation_18 | OemActivation_18 | OemActivation_18 | OemActivation_18 | OemActivation_18 | OemActivation_18 | OemActivation_18 | OemActivation_18 | OemActivation_18 | OemActivation_18 | OemActivation_18 | OemActivation_18 | OemActivation_18 | OemActivation_18 | OemActivation_18 | OemActivation_18 | OemActivation_18 | OemActivation_18 | OemActivation_18 | OemActivation_18 |
| OptionRomPolicy | OptionRomPolicy_08 | OptionRomPolicy_08 | OptionRomPolicy_08 | OptionRomPolicy_08 | OptionRomPolicy_08 | OptionRomPolicy_08 | OptionRomPolicy_08 | OptionRomPolicy_08 | OptionRomPolicy_08 | OptionRomPolicy_08 | OptionRomPolicy_08 | OptionRomPolicy_08 | OptionRomPolicy_08 | OptionRomPolicy_08 | OptionRomPolicy_08 | OptionRomPolicy_08 | OptionRomPolicy_08 | OptionRomPolicy_08 | OptionRomPolicy_08 | OptionRomPolicy_08 | OptionRomPolicy_08 | OptionRomPolicy_08 | OptionRomPolicy_08 | OptionRomPolicy_08 |
| PciBus | PciBus_28 | PciBus_28 | PciBus_28 | PciBus_28 | PciBus_28 | PciBus_28 | PciBus_28 | PciBus_28 | PciBus_28 | PciBus_28 | PciBus_28 | PciBus_28 | PciBus_28 | PciBus_28 | PciBus_28 | PciBus_28 | PciBus_28 | PciBus_28 | PciBus_28 | PciBus_28 | PciBus_28 | PciBus_28 | PciBus_28 | PciBus_28 |
| PlatformToDriver | PlatformToDriver_02 | PlatformToDriver_02 | PlatformToDriver_02 | PlatformToDriver_02 | PlatformToDriver_02 | PlatformToDriver_02 | PlatformToDriver_02 | PlatformToDriver_02 | PlatformToDriver_02 | PlatformToDriver_02 | PlatformToDriver_02 | PlatformToDriver_02 | PlatformToDriver_02 | PlatformToDriver_02 | PlatformToDriver_02 | PlatformToDriver_02 | PlatformToDriver_02 | PlatformToDriver_02 | PlatformToDriver_02 | PlatformToDriver_02 | PlatformToDriver_02 | PlatformToDriver_02 | PlatformToDriver_02 | PlatformToDriver_02 |
| RestoreSpecialBootOptions | RestoreSpecialBootOptions_04 | RestoreSpecialBootOptions_04 | RestoreSpecialBootOptions_04 | RestoreSpecialBootOptions_04 | RestoreSpecialBootOptions_04 | RestoreSpecialBootOptions_04 | RestoreSpecialBootOptions_04 | RestoreSpecialBootOptions_04 | RestoreSpecialBootOptions_04 | RestoreSpecialBootOptions_04 | RestoreSpecialBootOptions_04 | RestoreSpecialBootOptions_04 | RestoreSpecialBootOptions_04 | RestoreSpecialBootOptions_04 | RestoreSpecialBootOptions_04 | RestoreSpecialBootOptions_04 | RestoreSpecialBootOptions_04 | RestoreSpecialBootOptions_04 | RestoreSpecialBootOptions_04 | RestoreSpecialBootOptions_04 | RestoreSpecialBootOptions_04 | RestoreSpecialBootOptions_04 | RestoreSpecialBootOptions_04 | RestoreSpecialBootOptions_04 |
| RsdpPlus | RsdpPlus_11 | RsdpPlus_11 | RsdpPlus_11 | RsdpPlus_11 | RsdpPlus_11 | RsdpPlus_11 | RsdpPlus_11 | RsdpPlus_11 | RsdpPlus_11 | RsdpPlus_11 | RsdpPlus_11 | RsdpPlus_11 | RsdpPlus_11 | RsdpPlus_11 | RsdpPlus_11 | RsdpPlus_11 | RsdpPlus_11 | RsdpPlus_11 | RsdpPlus_11 | RsdpPlus_11 | RsdpPlus_11 | RsdpPlus_11 | RsdpPlus_11 | RsdpPlus_11 |
| SmiVariable | SmiVariable_10 | SmiVariable_10 | SmiVariable_10 | SmiVariable_10 | SmiVariable_10 | SmiVariable_10 | SmiVariable_10 | SmiVariable_10 | SmiVariable_10 | SmiVariable_10 | SmiVariable_10 | SmiVariable_10 | SmiVariable_10 | SmiVariable_10 | SmiVariable_10 | SmiVariable_10 | SmiVariable_10 | SmiVariable_10 | SmiVariable_10 | SmiVariable_10 | SmiVariable_10 | SmiVariable_10 | SmiVariable_10 | SmiVariable_10 |
| Serial Redirection | Terminal_25 | Terminal_25 | Terminal_25 | Terminal_25 | Terminal_25 | Terminal_25 | Terminal_25 | Terminal_25 | Terminal_25 | Terminal_25 | Terminal_25 | Terminal_25 | Terminal_25 | Terminal_25 | Terminal_25 | Terminal_25 | Terminal_25 | Terminal_25 | Terminal_25 | Terminal_25 | Terminal_25 | Terminal_25 | Terminal_25 | Terminal_25 |
| TseDefaultBootOrder | TseDefaultBootOrder_04 | TseDefaultBootOrder_04 | TseDefaultBootOrder_04 | TseDefaultBootOrder_04 | TseDefaultBootOrder_04 | TseDefaultBootOrder_04 | TseDefaultBootOrder_04 | TseDefaultBootOrder_04 | TseDefaultBootOrder_04 | TseDefaultBootOrder_04 | TseDefaultBootOrder_04 | TseDefaultBootOrder_04 | TseDefaultBootOrder_04 | TseDefaultBootOrder_04 | TseDefaultBootOrder_04 | TseDefaultBootOrder_04 | TseDefaultBootOrder_04 | TseDefaultBootOrder_04 | TseDefaultBootOrder_04 | TseDefaultBootOrder_04 | TseDefaultBootOrder_04 | TseDefaultBootOrder_04 | TseDefaultBootOrder_04 | TseDefaultBootOrder_04 |
| UefiBootOption | UefiBootOption_09 | UefiBootOption_09 | UefiBootOption_09 | UefiBootOption_09 | UefiBootOption_09 | UefiBootOption_09 | UefiBootOption_09 | UefiBootOption_09 | UefiBootOption_09 | UefiBootOption_09 | UefiBootOption_09 | UefiBootOption_09 | UefiBootOption_09 | UefiBootOption_09 | UefiBootOption_09 | UefiBootOption_09 | UefiBootOption_09 | UefiBootOption_09 | UefiBootOption_09 | UefiBootOption_09 | UefiBootOption_09 | UefiBootOption_09 | UefiBootOption_09 | UefiBootOption_09 |
| InfoReport | InfoReport_05 | InfoReport_05 | InfoReport_05 | InfoReport_05 | InfoReport_05 | InfoReport_05 | InfoReport_05 | InfoReport_05 | InfoReport_05 | InfoReport_05 | InfoReport_05 | InfoReport_05 | InfoReport_05 | InfoReport_05 | InfoReport_05 | InfoReport_05 | InfoReport_05 | InfoReport_05 | InfoReport_05 | InfoReport_05 | InfoReport_05 | InfoReport_05 | InfoReport_05 | InfoReport_05 |
| PauseKey | PauseKey_02 | PauseKey_02 | PauseKey_02 | PauseKey_02 | PauseKey_02 | PauseKey_02 | PauseKey_02 | PauseKey_02 | PauseKey_02 | PauseKey_02 | PauseKey_02 | PauseKey_02 | PauseKey_02 | PauseKey_02 | PauseKey_02 | PauseKey_02 | PauseKey_02 | PauseKey_02 | PauseKey_02 | PauseKey_02 | PauseKey_02 | PauseKey_02 | PauseKey_02 | PauseKey_02 |
| Usb | AmiUsb_28 | AmiUsb_28 | AmiUsb_28 | AmiUsb_28 | AmiUsb_29 | AmiUsb_28 | AmiUsb_29 | AmiUsb_29 | AmiUsb_29 | AmiUsb_29 | AmiUsb_29 | AmiUsb_29 | AmiUsb_29 | AmiUsb_29 | AmiUsb_29 | AmiUsb_29 | AmiUsb_29 | AmiUsb_29 | AmiUsb_29 | AmiUsb_29 | AmiUsb_29 | AmiUsb_29 | AmiUsb_29 | AmiUsb_29 |
| AhciRecovery | AhciRecovery_13 | AhciRecovery_13 | AhciRecovery_13 | AhciRecovery_13 | AhciRecovery_13 | AhciRecovery_13 | AhciRecovery_13 | AhciRecovery_13 | AhciRecovery_13 | AhciRecovery_13 | AhciRecovery_13 | AhciRecovery_13 | AhciRecovery_13 | AhciRecovery_13 | AhciRecovery_13 | AhciRecovery_13 | AhciRecovery_13 | AhciRecovery_13 | AhciRecovery_13 | AhciRecovery_13 | AhciRecovery_13 | AhciRecovery_13 | AhciRecovery_13 | AhciRecovery_13 |
| AmiNetworkPkg | AmiNetworkPkg_40 | AmiNetworkPkg_40 | AmiNetworkPkg_40 | AmiNetworkPkg_40 | AmiNetworkPkg_40 | AmiNetworkPkg_40 | AmiNetworkPkg_40 | AmiNetworkPkg_40 | AmiNetworkPkg_40 | AmiNetworkPkg_40 | AmiNetworkPkg_40 | AmiNetworkPkg_40 | AmiNetworkPkg_40 | AmiNetworkPkg_40 | AmiNetworkPkg_40 | AmiNetworkPkg_40 | AmiNetworkPkg_40 | AmiNetworkPkg_40 | AmiNetworkPkg_40 | AmiNetworkPkg_40 | AmiNetworkPkg_40 | AmiNetworkPkg_40 | AmiNetworkPkg_40 | AmiNetworkPkg_40 |
| UefiNetworkStack | UefiNetworkStack_40 | UefiNetworkStack_40 | UefiNetworkStack_40 | UefiNetworkStack_40 | UefiNetworkStack_40 | UefiNetworkStack_40 | UefiNetworkStack_40 | UefiNetworkStack_40 | UefiNetworkStack_40 | UefiNetworkStack_40 | UefiNetworkStack_40 | UefiNetworkStack_40 | UefiNetworkStack_40 | UefiNetworkStack_40 | UefiNetworkStack_40 | UefiNetworkStack_40 | UefiNetworkStack_40 | UefiNetworkStack_40 | UefiNetworkStack_40 | UefiNetworkStack_40 | UefiNetworkStack_40 | UefiNetworkStack_40 | UefiNetworkStack_40 | UefiNetworkStack_40 |
| PC Essentials | PcEssentials_01 | PcEssentials_01 | PcEssentials_01 | PcEssentials_01 | PcEssentials_01 | PcEssentials_01 | PcEssentials_01 | PcEssentials_01 | PcEssentials_01 | PcEssentials_01 | PcEssentials_01 | PcEssentials_01 | PcEssentials_01 | PcEssentials_01 | PcEssentials_01 | PcEssentials_01 | PcEssentials_01 | PcEssentials_01 | PcEssentials_01 | PcEssentials_01 | PcEssentials_01 | PcEssentials_01 | PcEssentials_01 | PcEssentials_01 |
| AmiBoardInfo | AmiBoardInfo_08 | AmiBoardInfo_08 | AmiBoardInfo_08 | AmiBoardInfo_08 | AmiBoardInfo_08 | AmiBoardInfo_08 | AmiBoardInfo_08 | AmiBoardInfo_08 | AmiBoardInfo_08 | AmiBoardInfo_08 | AmiBoardInfo_08 | AmiBoardInfo_08 | AmiBoardInfo_08 | AmiBoardInfo_08 | AmiBoardInfo_08 | AmiBoardInfo_08 | AmiBoardInfo_08 | AmiBoardInfo_08 | AmiBoardInfo_08 | AmiBoardInfo_08 | AmiBoardInfo_08 | AmiBoardInfo_08 | AmiBoardInfo_08 | AmiBoardInfo_08 |
| Recovery | Recovery_26 | Recovery_26 | Recovery_26 | Recovery_26 | Recovery_26 | Recovery_26 | Recovery_26 | Recovery_26 | Recovery_26 | Recovery_26 | Recovery_26 | Recovery_26 | Recovery_26 | Recovery_26 | Recovery_26 | Recovery_26 | Recovery_26 | Recovery_26 | Recovery_26 | Recovery_26 | Recovery_26 | Recovery_26 | Recovery_26 | Recovery_26 |
| RuntimeSmm | RuntimeSmm_03 | RuntimeSmm_03 | RuntimeSmm_03 | RuntimeSmm_03 | RuntimeSmm_03 | RuntimeSmm_03 | RuntimeSmm_03 | RuntimeSmm_03 | RuntimeSmm_03 | RuntimeSmm_03 | RuntimeSmm_03 | RuntimeSmm_03 | RuntimeSmm_03 | RuntimeSmm_03 | RuntimeSmm_03 | RuntimeSmm_03 | RuntimeSmm_03 | RuntimeSmm_03 | RuntimeSmm_03 | RuntimeSmm_03 | RuntimeSmm_03 | RuntimeSmm_03 | RuntimeSmm_03 | RuntimeSmm_03 |
| IntelArchitecture | IntelArchitecture_06 | IntelArchitecture_06 | IntelArchitecture_06 | IntelArchitecture_06 | IntelArchitecture_06 | IntelArchitecture_06 | IntelArchitecture_06 | IntelArchitecture_06 | IntelArchitecture_06 | IntelArchitecture_06 | IntelArchitecture_06 | IntelArchitecture_06 | IntelArchitecture_06 | IntelArchitecture_06 | IntelArchitecture_06 | IntelArchitecture_06 | IntelArchitecture_06 | IntelArchitecture_06 | IntelArchitecture_06 | IntelArchitecture_06 | IntelArchitecture_06 | IntelArchitecture_06 | IntelArchitecture_06 | IntelArchitecture_06 |
| SingleSegmentPciCfg2 | SingleSegmentPciCfg2_04 | SingleSegmentPciCfg2_04 | SingleSegmentPciCfg2_04 | SingleSegmentPciCfg2_04 | SingleSegmentPciCfg2_04 | SingleSegmentPciCfg2_04 | SingleSegmentPciCfg2_04 | SingleSegmentPciCfg2_04 | SingleSegmentPciCfg2_04 | SingleSegmentPciCfg2_04 | SingleSegmentPciCfg2_04 | SingleSegmentPciCfg2_04 | SingleSegmentPciCfg2_04 | SingleSegmentPciCfg2_04 | SingleSegmentPciCfg2_04 | SingleSegmentPciCfg2_04 | SingleSegmentPciCfg2_04 | SingleSegmentPciCfg2_04 | SingleSegmentPciCfg2_04 | SingleSegmentPciCfg2_04 | SingleSegmentPciCfg2_04 | SingleSegmentPciCfg2_04 | SingleSegmentPciCfg2_04 | SingleSegmentPciCfg2_04 |
| AmiSecureBootPkg | AmiSecureBootPkg_17 | AmiSecureBootPkg_17 | AmiSecureBootPkg_17 | AmiSecureBootPkg_17 | AmiSecureBootPkg_17 | AmiSecureBootPkg_17 | AmiSecureBootPkg_17 | AmiSecureBootPkg_17 | AmiSecureBootPkg_17 | AmiSecureBootPkg_17 | AmiSecureBootPkg_17 | AmiSecureBootPkg_17 | AmiSecureBootPkg_17 | AmiSecureBootPkg_17 | AmiSecureBootPkg_17 | AmiSecureBootPkg_17 | AmiSecureBootPkg_17 | AmiSecureBootPkg_17 | AmiSecureBootPkg_17 | AmiSecureBootPkg_17 | AmiSecureBootPkg_17 | AmiSecureBootPkg_17 | AmiSecureBootPkg_17 | AmiSecureBootPkg_17 |
| AmiTcgPkg | AmiTcgPkg_10 | AmiTcgPkg_10 | AmiTcgPkg_10 | AmiTcgPkg_10 | AmiTcgPkg_10 | AmiTcgPkg_10 | AmiTcgPkg_10 | AmiTcgPkg_10 | AmiTcgPkg_10 | AmiTcgPkg_10 | AmiTcgPkg_10 | AmiTcgPkg_10 | AmiTcgPkg_10 | AmiTcgPkg_10 | AmiTcgPkg_10 | AmiTcgPkg_10 | AmiTcgPkg_10 | AmiTcgPkg_10 | AmiTcgPkg_10 | AmiTcgPkg_10 | AmiTcgPkg_10 | AmiTcgPkg_10 | AmiTcgPkg_10 | AmiTcgPkg_10 |
| AmiTrustedFvPkg | AmiTrustedFvPkg_10 | AmiTrustedFvPkg_10 | AmiTrustedFvPkg_10 | AmiTrustedFvPkg_10 | AmiTrustedFvPkg_10 | AmiTrustedFvPkg_10 | AmiTrustedFvPkg_10 | AmiTrustedFvPkg_10 | AmiTrustedFvPkg_10 | AmiTrustedFvPkg_10 | AmiTrustedFvPkg_10 | AmiTrustedFvPkg_10 | AmiTrustedFvPkg_10 | AmiTrustedFvPkg_10 | AmiTrustedFvPkg_10 | AmiTrustedFvPkg_10 | AmiTrustedFvPkg_10 | AmiTrustedFvPkg_10 | AmiTrustedFvPkg_10 | AmiTrustedFvPkg_10 | AmiTrustedFvPkg_10 | AmiTrustedFvPkg_10 | AmiTrustedFvPkg_10 | AmiTrustedFvPkg_10 |
| AtaPassThru | AtaPassThru_13 | AtaPassThru_13 | AtaPassThru_13 | AtaPassThru_13 | AtaPassThru_13 | AtaPassThru_13 | AtaPassThru_13 | AtaPassThru_13 | AtaPassThru_13 | AtaPassThru_13 | AtaPassThru_13 | AtaPassThru_13 | AtaPassThru_13 | AtaPassThru_13 | AtaPassThru_13 | AtaPassThru_13 | AtaPassThru_13 | AtaPassThru_13 | AtaPassThru_13 | AtaPassThru_13 | AtaPassThru_13 | AtaPassThru_13 | AtaPassThru_13 | AtaPassThru_13 |
| Csm | Csm_7.84_21 | Csm_7.84_21 | Csm_7.84_21 | Csm_7.84_21 | Csm_7.84_21 | Csm_7.84_21 | Csm_7.84_21 | Csm_7.84_21 | Csm_7.84_21 | Csm_7.84_21 | Csm_7.84_21 | Csm_7.84_21 | Csm_7.84_21 | Csm_7.84_21 | Csm_7.84_21 | Csm_7.84_21 | Csm_7.84_21 | Csm_7.84_21 | Csm_7.84_21 | Csm_7.84_21 | Csm_7.84_21 | Csm_7.84_21 | Csm_7.84_21 | Csm_7.84_21 |
| CMOS Manager | CmosManager_13 | CmosManager_13 | CmosManager_13 | CmosManager_13 | CmosManager_13 | CmosManager_13 | CmosManager_13 | CmosManager_13 | CmosManager_13 | CmosManager_13 | CmosManager_13 | CmosManager_13 | CmosManager_13 | CmosManager_13 | CmosManager_13 | CmosManager_13.1 | CmosManager_13.1 | CmosManager_13.1 | CmosManager_13.1 | CmosManager_13.1 | CmosManager_13.1 | CmosManager_13.1 | CmosManager_13.1 | CmosManager_13.1 |
| FatBinPkg | FatBin_09 | FatBin_09 | FatBin_09 | FatBin_09 | FatBin_09 | FatBin_09 | FatBin_09 | FatBin_09 | FatBin_09 | FatBin_09 | FatBin_09 | FatBin_09 | FatBin_09 | FatBin_09 | FatBin_09 | FatBin_09 | FatBin_09 | FatBin_09 | FatBin_09 | FatBin_09 | FatBin_09 | FatBin_09 | FatBin_09 | FatBin_09 |
| FlashSmi | FlashSmi_12 | FlashSmi_12 | FlashSmi_12 | FlashSmi_12 | FlashSmi_12 | FlashSmi_12 | FlashSmi_12 | FlashSmi_12 | FlashSmi_12 | FlashSmi_12 | FlashSmi_12 | FlashSmi_12 | FlashSmi_12 | FlashSmi_12 | FlashSmi_12 | FlashSmi_12 | FlashSmi_12 | FlashSmi_12 | FlashSmi_12 | FlashSmi_12 | FlashSmi_12 | FlashSmi_12 | FlashSmi_12 | FlashSmi_12 |
| GpnvErrorLogging | GpnvErrorLogging_18 | GpnvErrorLogging_18 | GpnvErrorLogging_18 | GpnvErrorLogging_18 | GpnvErrorLogging_18 | GpnvErrorLogging_18 | GpnvErrorLogging_18 | GpnvErrorLogging_18 | GpnvErrorLogging_18 | GpnvErrorLogging_18 | GpnvErrorLogging_18 | GpnvErrorLogging_18 | GpnvErrorLogging_18 | GpnvErrorLogging_18 | GpnvErrorLogging_18 | GpnvErrorLogging_18.1 | GpnvErrorLogging_18.1 | GpnvErrorLogging_18.1 | GpnvErrorLogging_18.1 | GpnvErrorLogging_18.1 | GpnvErrorLogging_18.1 | GpnvErrorLogging_18.1 | GpnvErrorLogging_18.1 | GpnvErrorLogging_18.1 |
| HddSecurity | HddSecurity_34 | HddSecurity_34 | HddSecurity_34 | HddSecurity_34 | HddSecurity_34 | HddSecurity_34 | HddSecurity_34 | HddSecurity_34 | HddSecurity_34 | HddSecurity_34 | HddSecurity_34 | HddSecurity_34 | HddSecurity_34 | HddSecurity_34 | HddSecurity_34 | HddSecurity_34.1 | HddSecurity_34.1 | HddSecurity_34.1 | HddSecurity_34.1 | HddSecurity_34.1 | HddSecurity_34.1 | HddSecurity_34.1 | HddSecurity_34.1 | HddSecurity_34.1 |
| IScsi | IScsi_41 | IScsi_41 | IScsi_41 | IScsi_41 | IScsi_41 | IScsi_41 | IScsi_41 | IScsi_41 | IScsi_41 | IScsi_41 | IScsi_41 | IScsi_41 | IScsi_41 | IScsi_41 | IScsi_41 | IScsi_41 | IScsi_41 | IScsi_41 | IScsi_41 | IScsi_41 | IScsi_41 | IScsi_41 | IScsi_41 | IScsi_41 |
| InfoReport | InfoReport_06 | InfoReport_06 | InfoReport_06 | InfoReport_06 | InfoReport_06 | InfoReport_06 | InfoReport_06 | InfoReport_06 | InfoReport_06 | InfoReport_06 | InfoReport_06 | InfoReport_06 | InfoReport_06 | InfoReport_06 | InfoReport_06 | InfoReport_06 | InfoReport_06 | InfoReport_06 | InfoReport_06 | InfoReport_06 | InfoReport_06 | InfoReport_06 | InfoReport_06 | InfoReport_06 |
| KbcEmulation | KbcEmulation_13 | KbcEmulation_13 | KbcEmulation_13 | KbcEmulation_13 | KbcEmulation_13 | KbcEmulation_13 | KbcEmulation_13 | KbcEmulation_13 | KbcEmulation_13 | KbcEmulation_13 | KbcEmulation_13 | KbcEmulation_13 | KbcEmulation_13 | KbcEmulation_13 | KbcEmulation_13 | KbcEmulation_13 | KbcEmulation_13 | KbcEmulation_13 | KbcEmulation_13 | KbcEmulation_13 | KbcEmulation_13 | KbcEmulation_13 | KbcEmulation_13 | KbcEmulation_13 |
| Esrt | Esrt_03 | Esrt_03 | Esrt_03 | Esrt_03 | Esrt_03 | Esrt_03 | Esrt_03 | Esrt_03 | Esrt_03 | Esrt_03 | Esrt_03 | Esrt_03 | Esrt_03 | Esrt_03 | Esrt_03 | Esrt_03 | Esrt_03 | Esrt_03 | Esrt_03 | Esrt_03 | Esrt_03 | Esrt_03 | Esrt_03 | Esrt_03 |
| Scsi | Scsi_05 | Scsi_05 | Scsi_05 | Scsi_05 | Scsi_05 | Scsi_05 | Scsi_05 | Scsi_05 | Scsi_05 | Scsi_05 | Scsi_05 | Scsi_05 | Scsi_05 | Scsi_05 | Scsi_05 | Scsi_05 | Scsi_05 | Scsi_05 | Scsi_05 | Scsi_05 | Scsi_05 | Scsi_05 | Scsi_05 | Scsi_05 |
| GenoaSoCPkg | GenoaSoCPkg_14 | GenoaSoCPkg_15 | GenoaSoCPkg_15 | GenoaSoCPkg_15 | GenoaSoCPkg_16 | GenoaSoCPkg_15 | GenoaSoCPkg_17 | GenoaSoCPkg_17 | GenoaSoCPkg_18 | GenoaSoCPkg_18 | GenoaSoCPkg_19 | GenoaSoCPkg_19 | GenoaSoCPkg_19 | GenoaSoCPkg_20 | GenoaSoCPkg_20 | GenoaSoCPkg_21 | GenoaSoCPkg_21 | GenoaSoCPkg_23 | GenoaSoCPkg_23 | GenoaSoCPkg_24 | GenoaSoCPkg_25 | GenoaSoCPkg_25 | GenoaSoCPkg_25 | GenoaSoCPkg_26 |
| Nvme | Nvme_30 | Nvme_30 | Nvme_30 | Nvme_30 | Nvme_30 | Nvme_30 | Nvme_30 | Nvme_30 | Nvme_30 | Nvme_30 | Nvme_30 | Nvme_30 | Nvme_30 | Nvme_30 | Nvme_30 | Nvme_30.1 | Nvme_30.1 | Nvme_30.1 | Nvme_30.1 | Nvme_30.1 | Nvme_30.1 | Nvme_30.1 | Nvme_30.1 | Nvme_30.1 |
| On Flash Block Description (APTIO) - Secure Flash | 5.005_OfbdSecureFlash_009 | 5.005_OfbdSecureFlash_009 | 5.005_OfbdSecureFlash_009 | 5.005_OfbdSecureFlash_009 | 5.005_OfbdSecureFlash_009 | 5.005_OfbdSecureFlash_009 | 5.005_OfbdSecureFlash_009 | 5.005_OfbdSecureFlash_009 | 5.005_OfbdSecureFlash_009 | 5.005_OfbdSecureFlash_009 | 5.005_OfbdSecureFlash_009 | 5.005_OfbdSecureFlash_009 | 5.005_OfbdSecureFlash_009 | 5.005_OfbdSecureFlash_009 | 5.005_OfbdSecureFlash_009 | 5.005_OfbdSecureFlash_009 | 5.005_OfbdSecureFlash_009 | 5.005_OfbdSecureFlash_009 | 5.005_OfbdSecureFlash_009 | 5.005_OfbdSecureFlash_009 | 5.005_OfbdSecureFlash_009 | 5.005_OfbdSecureFlash_009 | 5.005_OfbdSecureFlash_009 | 5.005_OfbdSecureFlash_009 |
| On Flash Block Description (APTIO) | OFBD_26 | OFBD_26 | OFBD_26 | OFBD_26 | OFBD_26 | OFBD_26 | OFBD_26 | OFBD_26 | OFBD_26 | OFBD_26 | OFBD_26 | OFBD_26 | OFBD_26 | OFBD_26 | OFBD_26 | OFBD_26 | OFBD_26 | OFBD_26 | OFBD_26 | OFBD_26 | OFBD_26 | OFBD_26 | OFBD_26 | OFBD_26 |
| OpalSecurity | OpalSecurity_08 | OpalSecurity_08 | OpalSecurity_08 | OpalSecurity_08 | OpalSecurity_08 | OpalSecurity_08 | OpalSecurity_08 | OpalSecurity_08 | OpalSecurity_08 | OpalSecurity_08 | OpalSecurity_08 | OpalSecurity_08 | OpalSecurity_08 | OpalSecurity_08 | OpalSecurity_08 | OpalSecurity_08 | OpalSecurity_08 | OpalSecurity_08 | OpalSecurity_08 | OpalSecurity_08 | OpalSecurity_08 | OpalSecurity_08 | OpalSecurity_08 | OpalSecurity_08 |
| PauseKey | PauseKey_02 | PauseKey_02 | PauseKey_02 | PauseKey_02 | PauseKey_02 | PauseKey_02 | PauseKey_02 | PauseKey_02 | PauseKey_02 | PauseKey_02 | PauseKey_02 | PauseKey_02 | PauseKey_02 | PauseKey_02 | PauseKey_02 | PauseKey_02 | PauseKey_02 | PauseKey_02 | PauseKey_02 | PauseKey_02 | PauseKey_02 | PauseKey_02 | PauseKey_02 | PauseKey_02 |
| PeiPciEnumeration | PeiPciEnumeration_05 | PeiPciEnumeration_05 | PeiPciEnumeration_05 | PeiPciEnumeration_05 | PeiPciEnumeration_05 | PeiPciEnumeration_05 | PeiPciEnumeration_05 | PeiPciEnumeration_05 | PeiPciEnumeration_05 | PeiPciEnumeration_05 | PeiPciEnumeration_05 | PeiPciEnumeration_05 | PeiPciEnumeration_05 | PeiPciEnumeration_05 | PeiPciEnumeration_05 | PeiPciEnumeration_05 | PeiPciEnumeration_05 | PeiPciEnumeration_05 | PeiPciEnumeration_05 | PeiPciEnumeration_05 | PeiPciEnumeration_05 | PeiPciEnumeration_05 | PeiPciEnumeration_05 | PeiPciEnumeration_05 |
| SataDeviceInformation | SataDevInfo_04 | SataDevInfo_04 | SataDevInfo_04 | SataDevInfo_04 | SataDevInfo_04 | SataDevInfo_04 | SataDevInfo_04 | SataDevInfo_04 | SataDevInfo_04 | SataDevInfo_04 | SataDevInfo_04 | SataDevInfo_04 | SataDevInfo_04 | SataDevInfo_04 | SataDevInfo_04 | SataDevInfo_04 | SataDevInfo_04 | SataDevInfo_04 | SataDevInfo_04 | SataDevInfo_04 | SataDevInfo_04 | SataDevInfo_04 | SataDevInfo_04 | SataDevInfo_04 |
| SecureBoot,UEFI | SecureBoot_40 | SecureBoot_40 | SecureBoot_40 | SecureBoot_40 | SecureBoot_40 | SecureBoot_40 | SecureBoot_40 | SecureBoot_40 | SecureBoot_40 | SecureBoot_40 | SecureBoot_40 | SecureBoot_40 | SecureBoot_40 | SecureBoot_40 | SecureBoot_40 | SecureBoot_40 | SecureBoot_40 | SecureBoot_40 | SecureBoot_40 | SecureBoot_40 | SecureBoot_40 | SecureBoot_40 | SecureBoot_40 | SecureBoot_40 |
| SecureFlash,NIST SP800-147 | SecureFlash_30.1 | SecureFlash_30.1 | SecureFlash_30.1 | SecureFlash_30.1 | SecureFlash_30.1 | SecureFlash_30.1 | SecureFlash_30.1 | SecureFlash_30.1 | SecureFlash_30.1 | SecureFlash_30.1 | SecureFlash_30.1 | SecureFlash_30.1 | SecureFlash_30.1 | SecureFlash_30.1 | SecureFlash_30.1 | SecureFlash_30.1 | SecureFlash_30.1 | SecureFlash_30.1 | SecureFlash_30.1 | SecureFlash_30.1 | SecureFlash_30.1 | SecureFlash_30.1 | SecureFlash_30.1 | SecureFlash_30.1 |
| ShellBinPkg | ShellBinPkg_19 | ShellBinPkg_19 | ShellBinPkg_19 | ShellBinPkg_19 | ShellBinPkg_19 | ShellBinPkg_19 | ShellBinPkg_19 | ShellBinPkg_19 | ShellBinPkg_19 | ShellBinPkg_19 | ShellBinPkg_19 | ShellBinPkg_19 | ShellBinPkg_19 | ShellBinPkg_19 | ShellBinPkg_19 | ShellBinPkg_19 | ShellBinPkg_19 | ShellBinPkg_19 | ShellBinPkg_19 | ShellBinPkg_19 | ShellBinPkg_19 | ShellBinPkg_19 | ShellBinPkg_19 | ShellBinPkg_19 |
| Smbios | Smbios_31 | Smbios_32 | Smbios_32 | Smbios_32 | Smbios_32 | Smbios_32 | Smbios_32 | Smbios_32 | Smbios_32 | Smbios_32 | Smbios_32 | Smbios_32 | Smbios_32 | Smbios_32 | Smbios_32 | Smbios_32 | Smbios_32 | Smbios_32 | Smbios_32 | Smbios_32 | Smbios_32 | Smbios_32 | Smbios_32 | Smbios_32 |
| SmiFlash | SmiFlash_40 | SmiFlash_40 | SmiFlash_40 | SmiFlash_40 | SmiFlash_40 | SmiFlash_40 | SmiFlash_40 | SmiFlash_40 | SmiFlash_40 | SmiFlash_40 | SmiFlash_40 | SmiFlash_40 | SmiFlash_40 | SmiFlash_40 | SmiFlash_40 | SmiFlash_40 | SmiFlash_40 | SmiFlash_40 | SmiFlash_40 | SmiFlash_40 | SmiFlash_40 | SmiFlash_40 | SmiFlash_40 | SmiFlash_40 |
| SMM Support | Smm_09 | Smm_09 | Smm_09 | Smm_09 | Smm_09 | Smm_09 | Smm_09 | Smm_09 | Smm_09 | Smm_09 | Smm_09 | Smm_09 | Smm_09 | Smm_09 | Smm_09 | Smm_09 | Smm_09 | Smm_09 | Smm_09 | Smm_09 | Smm_09 | Smm_09 | Smm_09 | Smm_09 |
| SmmConfidentialMemModule | SmmConfidentialMemModule_02 | SmmConfidentialMemModule_02 | SmmConfidentialMemModule_02 | SmmConfidentialMemModule_02 | SmmConfidentialMemModule_02 | SmmConfidentialMemModule_02 | SmmConfidentialMemModule_02 | SmmConfidentialMemModule_02 | SmmConfidentialMemModule_02 | SmmConfidentialMemModule_02 | SmmConfidentialMemModule_02 | SmmConfidentialMemModule_02 | SmmConfidentialMemModule_02 | SmmConfidentialMemModule_02 | SmmConfidentialMemModule_02 | SmmConfidentialMemModule_02 | SmmConfidentialMemModule_02 | SmmConfidentialMemModule_02 | SmmConfidentialMemModule_02 | SmmConfidentialMemModule_02 | SmmConfidentialMemModule_02 | SmmConfidentialMemModule_02 | SmmConfidentialMemModule_02 | SmmConfidentialMemModule_02 |
| TCG2 | TCG2_29 | TCG2_29 | TCG2_29 | TCG2_29 | TCG2_29 | TCG2_29 | TCG2_29 | TCG2_29 | TCG2_29 | TCG2_29 | TCG2_29 | TCG2_29 | TCG2_29 | TCG2_29 | TCG2_29 | TCG2_29 | TCG2_29 | TCG2_29 | TCG2_29 | TCG2_29 | TCG2_29 | TCG2_29 | TCG2_29 | TCG2_29 |
| FixedBootOrder | FixedBootOrder_21 | FixedBootOrder_21 | FixedBootOrder_21 | FixedBootOrder_21 | FixedBootOrder_21 | FixedBootOrder_21 | FixedBootOrder_21 | FixedBootOrder_21 | FixedBootOrder_21 | FixedBootOrder_21 | FixedBootOrder_21 | FixedBootOrder_21 | FixedBootOrder_21 | FixedBootOrder_21 | FixedBootOrder_21 | FixedBootOrder_21 | FixedBootOrder_21 | FixedBootOrder_21 | FixedBootOrder_21 | FixedBootOrder_21 | FixedBootOrder_21 | FixedBootOrder_21 | FixedBootOrder_21 | FixedBootOrder_21 |
| AmiTsePkg | AmiTsePkg_2_22_1285 | AmiTsePkg_2_22_1285 | AmiTsePkg_2_22_1285 | AmiTsePkg_2_22_1285 | AmiTsePkg_2_22_1285 | AmiTsePkg_2_22_1285 | AmiTsePkg_2_22_1285 | AmiTsePkg_2_22_1285 | AmiTsePkg_2_22_1285 | AmiTsePkg_2_22_1285 | AmiTsePkg_2_22_1285 | AmiTsePkg_2_22_1285 | AmiTsePkg_2_22_1285 | AmiTsePkg_2_22_1285 | AmiTsePkg_2_22_1285 | AmiTsePkg_2_22_1285 | AmiTsePkg_2_22_1285 | AmiTsePkg_2_22_1285 | AmiTsePkg_2_22_1285 | AmiTsePkg_2_22_1285 | AmiTsePkg_2_22_1285 | AmiTsePkg_2_22_1285 | AmiTsePkg_2_22_1285 | AmiTsePkg_2_22_1285 |
| AMIDebuggerPkg | AMIDebuggerPkg_46 | AMIDebuggerPkg_46 | AMIDebuggerPkg_46 | AMIDebuggerPkg_46 | AMIDebuggerPkg_46 | AMIDebuggerPkg_46 | AMIDebuggerPkg_46 | AMIDebuggerPkg_46 | AMIDebuggerPkg_46 | AMIDebuggerPkg_46 | AMIDebuggerPkg_46 | AMIDebuggerPkg_46 | AMIDebuggerPkg_46 | AMIDebuggerPkg_46 | AMIDebuggerPkg_46 | AMIDebuggerPkg_46 | AMIDebuggerPkg_46 | AMIDebuggerPkg_46 | AMIDebuggerPkg_46 | AMIDebuggerPkg_46 | AMIDebuggerPkg_46 | AMIDebuggerPkg_46 | AMIDebuggerPkg_46 | AMIDebuggerPkg_46 |
| Debugger | Debugger_46 | Debugger_46 | Debugger_46 | Debugger_46 | Debugger_46 | Debugger_46 | Debugger_46 | Debugger_46 | Debugger_46 | Debugger_46 | Debugger_46 | Debugger_46 | Debugger_46 | Debugger_46 | Debugger_46 | Debugger_46 | Debugger_46 | Debugger_46 | Debugger_46 | Debugger_46 | Debugger_46 | Debugger_46 | Debugger_46 | Debugger_46 |
| CryptoPkg | CryptoPkg_46 | CryptoPkg_46 | CryptoPkg_46 | CryptoPkg_46 | CryptoPkg_46 | CryptoPkg_46 | CryptoPkg_46 | CryptoPkg_46 | CryptoPkg_46 | CryptoPkg_46 | CryptoPkg_46 | CryptoPkg_46 | CryptoPkg_46 | CryptoPkg_46 | CryptoPkg_46 | CryptoPkg_46 | CryptoPkg_46 | CryptoPkg_46 | CryptoPkg_46 | CryptoPkg_46 | CryptoPkg_50 | CryptoPkg_50 | CryptoPkg_50 | CryptoPkg_50 |
| TcgStorageSecurity | CryptoPkg_46 | CryptoPkg_46 | CryptoPkg_46 | CryptoPkg_46 | CryptoPkg_46 | CryptoPkg_46 | CryptoPkg_46 | CryptoPkg_46 | CryptoPkg_46 | CryptoPkg_46 | CryptoPkg_46 | CryptoPkg_46 | CryptoPkg_46 | CryptoPkg_46 |  | TcgStorageSecurity_17.1 | TcgStorageSecurity_17.1 | TcgStorageSecurity_17.1 | TcgStorageSecurity_17.1 | TcgStorageSecurity_17.1 | TcgStorageSecurity_17.1 | TcgStorageSecurity_17.1 | TcgStorageSecurity_17.1 | TcgStorageSecurity_17.1 |
| Bug fixes / Modified | Initial Version | Implement SMBIOS Type 0 EC version. | Fix CBSSetupData module cannot be workable to enable CBS_RS_SUPPORT in OEMBOARD.sdl for OCP. | Fix system cannot boot into setup menu by serial console when adding IpmiExtended module. | Upgrade AMI label to 5.27_GenoaCrb_0ACQT012. | Rollback to F0TG1A03. | Follow customer request to update SMBIOS Type17 DeviceLocator and BankLocator. | Enable "RELEASE_MODE_SYMBOL_SUPPORT" to support source level debug in release build mode. | Fix incorrect format of last boot memory error | Fix Write CRC UCE SEL not reported after F0TG_arn038_dv01, also update the SEL format | Make it able to control all PCIe port's speed under Setup Menu before PVT phase | Fixed that SMBIOS type 1 ProductName will discard FRU ProductInfoArea ProductPartModelNumber if it existed. | Follow PCIe SPEC to check if Pcie Extended Next Capability Offset is invalid. | Upgrade AMI label to 5.27_GenoaCrb_0ACQT016. | Display "No Bootable Device Detected." in Quiet Boot screen. | Fix missing string data in SMBIOS type1 when SMBIOS_TABLES_BUILD_TYPE set to 1. | Implement PXE/HTTP fail SEL when no media present. | Fix incorrect severity & type in PMIC error BERT log | Based on BIOS common feature to set SMBIOS type 4 MaxSpeed to 4000 directly. | Upgrade AMI label to 5.27_GenoaCrb_0ACQT019. | Upgrade AMI label to 5.27_GenoaCrb_0ACQT020. | Follow AMD Genoa Errata to add patch to fix known issues.   - Issue #1 - UD#/GP#/Segfault observed in SPEC06 GOBMK   - Issue #2 – RIP corruption observed with aliased page mappings of different sizes. | Follow DM/SI's request to modify PCIe Initial preset hint from P8 to P6 on PVT MB. | Fix PSP FW version in Type11 do not sync with PSP FW version in BIOS setup. |
|  |  | Set default to DHCP IPV6 DUID-LLT by PCD for OCP. | Update new CBSgenerate.exe to support to modify AmdCbsForm.vfr and ApcbAutoGen.h. | Disable time sync event from BIOS. | Follow OCP specification to update SMBIOS type 4/11. | Base on 1A03 to add to change the default UEFI Boot Priority sequence for F0TG. | Add Token "OEM_TYPE17_UPDATE_BANKLOCATOR" to control BankLocator format. | Add a setup item to adjust PCIe link speed of M.2 boot drive. | Use actual channel number instead of UMC number in unified memory SEL. | Fix FRU Chassis Part Number is not match SMBIOS type 3 Version issue. | Correct the PMIC filter condition | Modify UID of UAR2 to prevent conflict in ACPI DSDT table | Implement 500ms delay for IPMI_APP_GET_SELFTEST_RESULTS retry interval to prevent stressing BMC. |  | Implement SMBIOS type45. | Change type2 location in chassis token name for SMBIOS_TABLES_BUILD_TYPE set to 1. | Remove unnecessary library and rename to CBSSetupData_OCP for OCP. | Follow the latest definition of the OEM IPMI command to send MAC with Bus/Dev/Fun of LAN port to BMC. | Follow SI request to adjust I3C Configuration default value. | Enable hotplug and set bus resource padding to reserve bus assignment. | Follow DM request to enable PcdMpioPostMessageSupport to let PERST# de-assertion to LTSSM detect is less than 100ms for socket 1 ports. | Follow customer's request to set PMIC_29 and PMIC_2A to force to DCM mode from FCCM mode. | Remove the Location in chassis string space to meet SMBIOS spec. | Implement Boot Time PPR request SEL. |
|  |  | Implement OEM module "UpdateOEMID" to activate OA2 feature. | Add OEM module "SystemInfoToBmc". | Correct ManufacturerId to 0xA015 for OCP open BMC. | Change the default UEFI Boot Priority sequence for F0TG. | Base on 1A03 to add to set APML SB-TSI to I2C mode for OCP. | Token to control PCIe port enable/disable feature. | Follow customer's request to enable SSC for F0TG. | Update the coding style in OemBoardPkg\CBSSetupData\eSetupStones.xml for future convenient comparison. | W/A for fixed boot order priorities will show more boot option if enter by user password. | Implement OEM AER root error check for DPC Unified SEL. | Let system record SEL when PXE boot option load failed. | Enable Dimm looping feature. |  | Fix build error when SMBIOS_TABLES_BUILD_TYPE set to 1. | Enable TPM SPI DI timeout support bit for OCP project to prevent the system hang without TPM device. | Follow Http(s) boot flow in requirement spec to change DEFAULT_MEDIA_DETECT_COUNT to 3. | Add missing memory pool free for CXL error handler | Make _DSM Function 0x0D return to RP even if an error occurs on the DSP. | Follow customer request to disable GHES-Assist for OCP project. | Update SMBIOS type 9 for SMBIOS v3.5 definition. | Correct HTTP error code to 0x63 from 0x99. | Implement looping POST code and SEL log when DIMM population error and DIMM disable condition. | Follow RC to recover APCB tokens after OEM IPMI boot clear CMOS. |
|  |  | Enable DEFAULT_SHOW_HIDDEN_OPTION for OCP. | SMBIOS Type-1 system information "Product Name" info incorrect. | Optimized the code to display FRU in setup. | Set APML SB-TSI to I2C mode for OCP. |  | Change OCP NIC device SlotType to PCIe Gen4 X16. | Add OEM IPMI Cmos clear function. | Mask PCIe UR and advisory non-fatal error. | Follow SI standard SPEC and add Token to modify minimum of Setup Prompt Timeout to 1. | Enable EDR DPC event logging for OCP. | Follow ERRATUM #1437 to add B0/B1 microcode to resolve "Symmetric Multi Threading System With Different CS.base Values May Behave Unpredictably" issue. - | Modify data type of loop counter from UNIT8 to UINT32 to avoid infinite loop. |  | Enable HMAT table after AGESA 1.0.0.3 fixed hang 0x92 problem | Follow newsletter Genoa Weekly Updates-51-2022-12-13.pdf to add “GenoaPI-SP5_1.0.0.3_Patch_1.zip” patch. | Follow GTT to modify SMBIOS type9 device name string. | Implement PCIe failure event SEL. | Follow SI Std to hide some option under Advanced and Chipset page. | Follow customer request to modify PPR SEL log. | Add "OemDefaultBootOrder" to let system always boot into 09:00.0 boot drive. | Fix duplicated CE report when fatal/non-fatal error injected after correctable error injection |  | Modify algorithm for device's Data Link status update for DPC trigger flow to prevent DPC fail. |
|  |  | Follow OCP specification to set the default setting for [Do NOTHING] before PVT and [RESET] for PVT. | Add Retry 2 times if FRU checksum or length is not correct. | Use token OEM_PCIE_SPEED_CONTROL to set PCIe speed limit to Gen5. | Fix build error to use token DEFAULT_OEM_APML_SBTSI_SLAVE_MODE instead of APCB_TOKEN_UID_APML_SBTSI_SLAVE_MODE_VALUE. |  | Get CPU0/1's PPIN by StartupThisAP of MpServices. | Implement IPMI OEM "Set PPIN" (0x30/00,0x77). | Implement a text item to substitute "CurrentACRecoveryMode" | Disable that always preserve the Network Stack Configuration and Boot Order. | Set condition for OEM AER root error check. | Follow customer's request to set TDP/PPT default as 400W. | Follow customer's request to enable AFC for Memeye test on EVT/DVT phase |  | Fix redundant invalid boot order sel due to incorrect boot device count. | Modify PXE SEL error code return value. | Automatically detect board type(GPIO) to load PCIe margin setting of 8 re-timer MB or 2 re-timer MB in CPM table. | Follow customer's request to swap CPU0 P2/P4 BDF assignment to align with GT-T's boot drive BDF as 01:00.0. | Change slot threshold number for more boot device to unify boot option prefix. | Upgrade 1006 patch to resolve S1G1 port booting time around 20min issue. | Fix SMBIOS Type9 of under SWB E1.S mapping issue. | Always update dynamic CBS options to prevent unsupported options from being listed in SCE dump. |  | Upgrade AMI label to 5.27_GenoaCrb_0ACQT021. (AGESA 1008) |
|  |  | Follow customer spec to modify setup menu string "COM0" and "COM1". | Update SMBIOS type 1 Product Name field to be ProductName + ProductModelNumber. | Fix PCIe speed cannot achieve to Gen5. | Update SMBIOS type2 "Location in Chassis". |  | Follow PCIe spec to configure Uncorrectable Error Severity. | Implement WaitBmcReadyDxe function to OEM moudule. | Set silicon power policy setup "Ac Loss Control" to [Always OFF] for OCP. | To implement timeout countdown based on Setup Prompt Timeout. | Add PCIE device and update ASLfile for porting EDR. | Fix POST code is empty during system AC cycle on SOL. | Remove override on Link Speed Capability when PCIe port control feature is enabled for all ports |  | Modify string minsize to 0 to avoid warning message when import SCE configuration. | Implement multi board feature for using different APCB settings. |  | Filter out Broadcom switch when end device did not in use. | Fix system will not do endless boot loop when there is no other bootable device. | Modified  IO size to avoid re-allocate resource and reboot at postcode [95]. | Based on Genoa interlock to set SMBIOS type 4 MaxSpeed to 4100. | Implement Enable Source debug level in Release mode. |  | Follow AMD SN-7005 to include microcode patch for Genoa/Bergamo. |
|  |  | Follow customer's spec to disable Quiet Boot for OCP. | Fix TPM cannot detect in setup menu. |  | Using "SmbiosUpdate" module to update smbios type17 DeviceLocator, BankLocator and AssetTag field. |  | Upgrade AMI label to 5.27_GenoaCrb_0ACQT013. | Fix NIC device SlotID not show correctly in BIOS Setup. | Filter non-error PMIC status in OS dmesg | Follow SI Std to hide some Setup items under Save & Exit page and Server Mgmt page | Resolved Uncorrected PCIE Error cannot be reported when EDR dpc enable. | Follow customer's request to modify .rom to .BIN for OCP project. | Modify "Server Mgmt" page and sub-page layout to standard. |  | Follow customer's request to get certificate from BMC for HTTPS booting. | Add "MultiBoard" module to support ABL debug mode by switching GPIO. |  | Upgrade AMI label to 5.27_GenoaCrb_0ACQT018. | Revert slot ID of the CPU0 P2 and P4 port to slot ID of never exchanged previous locations. | Fix PcieSel failure detail for dpc condition wrong. | Re-define PCIe RAS SEL code flow. | Follow customer to Set MaxReadReq to 4096B for all root ports due to affecting NIC performance. |  | Follow Meta BIOS requirement SPEC to add Additional PPR Info Log to SEL format. |
|  |  | Follow customer's spec to set boot timeout to "7" for OCP. | Modified SPI_CPU0_TPM_CS_N to GPIO_PU_PD_DIS as HW had already pulled up to 1.8V. |  | Follow OCP Universal DIMM table to update DIMM location format for OCP projects. |  | Update SMBIOS type1 Wakeup type for OCP. | Fix Boot device string size not correct. | Fix build error when PLATFORM_SELECT is Titanite | Follow SI Std to hide some Setup items under Boot page & Chipset page | Follow AMD suggestion to modify MaxDxioGen to DxioGenMaxSupported. | Fix BIOS hang at 0x9A when BMC continuously return 0x81 with FRU Read command. | Modify behavior of input invalid IP on IPv6 address to remain previous valid IP instead of replaced by ::::::: |  | Add TOKEN "NOT_SEPERATE_SAVED_CERT" to control if support customer certificate combination file. | Follow customer requirement to add Memory Parity error PCC 0/1 Sel log. |  | Follow AGESA 1003 to update RAS message output | Update root port routing table to support EDR on each RP. | Follow customer requirement spec to define Password cleared by jumper POST event to unified SEL. | Set PcdMpioPostMessageSupport to false to avoid hang postcode 15 or B000A954 during AC cycle. | Follow customer request to default enable boot time PPR. |  | Fix that Slot ID and BDF of the smbios type9 didn't align with Debug runbook and lspci. |
|  |  | Implement "HDD Security Erase" option. | Follow SI Std to enable Security Device Support. |  | Implement looping POST code and SEL log when DIMM init fail. |  | Follow SI standard to display "NO Security Device Found" when TPM is disabled. |  | Fix ROM Size in Type 0 mismatch with actual ROM Size. | Follow BMC OEM SPEC to update the code of DDR5. | Follow OCP MB silkscreen to modify Frutext information. | Grayout "Erase SEL" for OCP as BMC doesn't support this function. | Follow Standard document to modify the behavior of setting IPv4 into previous address while insert invalid address. |  | Follow BIOS requirement SPEC to set ECC Correctable error threshold default value for OCP project. | Fixed multi PPR(Post Package Repair) Sel log. |  | Fix replacing boot device to [Disable] when using IPMI command to set 3 unsupported devices. | Add RISER_SLOT_NAMEING3v5_SUPPORT token to avoid some parameter wasn't referred to build error. | Fix SMBIOS Type9 of under SWB E1.S mapping issue. | Fix xGMI link speed cannot measure up on 32 GT/s. |  |  | Follow Meta BIOS Requirement SPEC to implement looping POST code when boot time PPR fail. |
|  |  | Use token to control BMC firmware version format as {Major version}.{Minor version}.{Test version}. | Correct Smbios Type 16 Maximum Capacity for F0TG. |  | Implement "Block SID Authentication" and "Security Freeze Lock" setup item for OCP project. |  | Follow SMBIOS SPEC to assign string number for SMBIOS Type 17 and fix incorrect Part number. |  | Use token to control year of system date input range from 2000 to 2097. | Follow AMD suggestion to limit P4/P5 root port speed to GEN3. | Follow SI Std to hide some Setup items under Advanced page | Implement OEM feature to preserve NIC0 PXE boot. | Correct IPv6 function and display info |  |  | Upgrade AMI label to 5.27_GenoaCrb_0ACQT017. |  | Follow customer request to modify SMBIOS Type17 BankLocator channel part to UMC number from board channel. | Fix system will boot fail with POST code EE0000B0. |  |  |  |  | Enable AMD ACT feature for checking APCB, PCD value. |
|  |  | Let POST info (including error info) always show after hot key message | Implement an OEM module that use to clear PCIe Device, AER status and PCIe Lane Error Status Register at POST end. |  | Add POST Error A10B for TPM Selftest fail. |  | Define CMOS/NVRAM configuration cleared POST event to unified SEL. |  | Fix HII Database size isn't enough to cause error when using AMISCE tool. | Fix build error to add correct token "DEFAULT_OEM_RELEASE_SPD_CTRL". | Follow BIOS_OEM_Feature_Checklist_v0.02 to add necessary fundamental token/elink setting. | Follow customer's request to disable IPV4 for OCP as default. | Add CSM condition for non-CSM projects build error problem. |  |  | Follow DM and SI's requirement to limit P0 port's Final preset on P4 and P5. |  | Add debug message to dump PCI Base/Limit value to see if "NeedReallocate" condition match. | Porting ESPI UART default to 0x2F8 from 0x3F8 for late DXE (debug mode). |  |  |  |  | Follow AMD ADDC white paper to modify related 3 BIOS settings to support ADDC feature (aka Crashdump feature). |
|  |  | Implement POST messages of F2/F11/F12 hotkey. | Change aspeed2600's Index port and Data port to 2E/2F. |  | Add DEBUG_GPIO to control enable/disable DebugPrint. |  | Add supported POST Error. |  | Modified "Bmc self test log" to "BMC self test log" to align with "BMC" word of other options. | Fix CPU Part Number info in Type 4 is not get from CPU PN. | Remove SMBIOS type 44 for OCP project, and remove an unused token MC_HOST_INTERFACE | Avoid CX7 NICs causing system to get stuck in the grub menu. | Remove SATA-CDROM support in OemIpmiBoot module |  |  |  |  | Remove GenoaPI-SP5_1.0.0.3_Patch_1. | Grayout BMC Network Configuration BIOS setup page since openBMC not support. |  |  |  |  |  |
|  |  | Follow customer's SPEC to show CPU and Mem information in the end of post for OCP. |  |  | Follow costomer's request to implement PXE boot fail SEL. |  | Remove redundant display message (BIOS version) on POST screen. |  | Upgrade AMI label to 5.27_GenoaCrb_0ACQT014. | Follow EIP#704393 to remove superfluous code to resolve adjusting Bottom IO issue. | Add back missing code in AmiTseHddSecurity.c to enable case sensitive for SATA HDD password. | Add PPR(Post Package Repair) Sel log. | Remove redundant UpdateSmbiosType1UUID from SmbiosUpdate OEM module. |  |  |  |  | Follow customer's request to set Determinism Control default as Power. | Set Unified ECC SEL dimm location always to 0. |  |  |  |  |  |
|  |  | Implement 'Slot # ' as prefix for UEFI NVMe boot option. |  |  | Add setup item to inhibit PXE Sel log. |  | Remove wait time message in InfoReport Module for OCP. |  | Restore original log mechanism in OemErrorLogEventMemTest to fix abnormal SEL for DDR training error. | Change BMC ready pin to low active to align cpld. | Add Performance Measurement support for AMIPRD dump to measure POST time. | Fix boot option string length not enough in BIOS Setup fixed boot order page. | Fix SEL was not recorded when inject PCIe error on NIC. |  |  |  |  | Implement EDR on DSP to trigger and activate DPC control bit on downstream port by _DSM function C. | Follow EIP#709022 to fix some module can't get correct duration in AMIPRD. |  |  |  |  |  |
|  |  | Implement OEM_SET_POST_START_CMD in PEI and DXE phase. |  |  | Implement CPLD/Bridge IC FW version in setup main page. |  | Fix system will stop in POST long time for OCP. |  | Follow SI Standard to rename OS Boot device name. | Adjust CPU1 RB1's below4G to avoid system hanging and rebooting when system connect with SWB and GPU. | Follow SI Std to hide some Setup items under Advanced Page:Trusted Computing/ Serial Port Console Redirection/ SIO Common Setting | Modify SW SSD DevPathToText to fix smbios show "in Use" if device not connect. | Enable EDPC control by default. |  |  |  |  | Implement EDR on DSP to return downstream port by _DSM function D if DSP's DPC status was triggered. |  |  |  |  |  |  |
|  |  | update FixedBootOrder_21 to FixedBootOrder_24. |  |  | Add F0TG SMBIOS Type9 slot list. |  | Add WaitBMCReady function in DXE. |  | Bug fixed incorrect severity for AMD root port due to Device Status doesn't set (DXE phase). | Implement OemIpmiInitAfterBmcReadyDxe driver in WaitBmcReadyDxe. | Fix bmc cannot get dimm's temperature and watts by APML due to wrong GPIO settings. | Follow WW45 newsletter to add patch for GenoaPI-1002 ABL Update. | Set DpcTriggerEnable as 2 to cover non-fatal and fatal error. |  |  |  |  | Implement EDR on DSP error handling to scan whether there is any DPC triggered by downstream port. |  |  |  |  |  |  |
|  |  |  |  |  |  |  |  |  | Clear 'Bit 6 - Capability Structure Status Valid' if PCIe capability isn't supported. | Set TotalErrCountFor1stErrID always to 0 | Disable NVMe boot order group for all projects |  | Set AmiSetupNvLock_SUPPORT" to 0 for OCP projects |  |  |  |  | Implement EDR on DSP to reassign pcie bus address from OS by _OST. |  |  |  |  |  |  |
|  |  | Modify help string for setup option "Setup Prompt Timeout" default value is 7 from 5 seconds. |  |  | Implement OCP format PCIe/Mca/Mem error log. |  | Fix PciePortCtl function failed issue. |  | Correct Slot ID and IRQ number. | Force SMBIOS type 11 string 6 (2nd CPU's PPIN) to be empty if only 1 socket is installed | Implement PMIC SEL as OCP unified memory format |  | Modify SMBIOS Type9 all devices configuration for SWB B0. |  |  |  |  | Implement EDR on DPC to check root port AER register first when Single error received. |  |  |  |  |  |  |
|  |  | Adjust "quiet boot" position after change AmiTse order to the last one in SETUP_DEFINITIONS. |  |  | Add F0TG SMBIOS Type41 onboard device list. |  |  |  | Related to WaitBmcReadyDxe function Enable FRB2 in Dxe. | Fine-tune GPIO setting to align with CPLD. | Fix system will stop in DIMM looping POST code when DIMM error is not init fail. |  | Add Http Device to OemIpmiBootDxe |  |  |  |  | Implement EDR on DPC to log event for root port. |  |  |  |  |  |  |
|  |  | Modify "Setup Prompt Timeout" range to 1~10. |  |  | Based on customer request to update DIMM post code. |  |  |  | Modify SMBIOS Type 2 "Location In Chassis" string. | Follow customer request to switch IPV4 and IPV6 HTTP and PXE boot order | Implement sending flash info to bmc |  | Follow customer's request to implement HTTP boot fail SEL. |  |  |  |  | Implement EDR on DSP to trigger SCI and continue to complete PcieErrorLog() if Dpc Trigger Status was set. |  |  |  |  |  |  |
|  |  | To implement timeout countdown based on Setup Prompt Timeout. |  |  | Improve ErrDimmLoc to cover multi-socket platform. |  |  |  | Support output Post Code through SOL. |  | Fix BIOS POST code show error message after clear CMOS by jummper. |  | Modify PXESELLogInhibition module to NetworkSELLogInhibition for supporting PXE and HTTP boot fail SEL. |  |  |  |  | Add condition to show root error status if PCIe device type is RootComplex for OCP Unified SEL |  |  |  |  |  |  |
|  |  | Modified string of NO_BOOT_OPTIONS to "No Bootable Device Detected" in POST report when system no boot device. |  |  | Remove AMD generic SMBIOS type 18/20/40. |  |  |  | Sync with Milan code to define APCB_TOKEN_UID_DF_BOTTOMIO_VALUE and BLDCFG_DF_BOTTOM_IO as MCT_BOTTOM_IO_VALUE. |  | Enable pciexpwakedis in PM register for WOL function |  | Adjust CPU1 RB0's below4G to avoid rebooting when system connect with EVT/DVT SWB and GPU. |  |  |  |  |  |  |  |  |  |  |  |
|  |  | Move the order of AmiBootOrder.sd behind AmiTse.sd in SETUP_DEFINITIONS for setup items in "Save & Exit" got the original order for OCP. |  |  | Fix HII Database size isn't enough when using AMISCE tool. |  |  |  | Add per project build log into veb. |  | Implement ACPI _PRW method for OCP NIC card WOL function. |  | Add E1.S boot drive. |  |  |  |  |  |  |  |  |  |  |  |
| Bug fixes / Modified |  | Add CBSSetupData_OCP Module to control CBS setup by XML for OCP. |  |  |  |  |  |  | Adjust MMIO below 4G resource to resolve booting windows server led to blue screen issue as ACPI_BIOS_ERROR. |  | Correct GPIO settings. |  |  |  |  |  |  |  |  |  |  |  |  |  |
|  |  | Use token OEM_PSP_ERROR_INJ_SUPPORT to set [PSP error injection support] to true OCP. |  |  |  |  |  |  | Follow GENOA channel number to send the system info to BMC and remove the DimmChannelMap from SEL log |  | Update missing OCP_NIC.asl file. |  |  |  |  |  |  |  |  |  |  |  |  |  |
|  |  | Re-add BaudRateModification module for OCP. |  |  |  |  |  |  |  |  | Follow customer's request to enable AFC for Memeye test on EVT/DVT phase for F0TG. |  |  |  |  |  |  |  |  |  |  |  |  |  |
|  |  | Update InfoReport_06 to InfoReport_07. |  |  |  |  |  |  |  |  | Disable BT/SSIF/IPMB IPMI interface. |  |  |  |  |  |  |  |  |  |  |  |  |  |
|  |  | Update UefiBootOption_09 to UefiBootOption_10. |  |  |  |  |  |  |  |  | Modify PXE SEL definition to meet BIOS Requirement Spec 0.8. |  |  |  |  |  |  |  |  |  |  |  |  |  |
|  |  | Add "OemIpmiBoot" module. |  |  |  |  |  |  |  |  | Follow EE request set AGPIO116 for BMC reset pin and Correct GPIO settings. |  |  |  |  |  |  |  |  |  |  |  |  |  |
|  |  | Add "OemBootOption" module. |  |  |  |  |  |  |  |  | Make all error code to be configured to correct address. |  |  |  |  |  |  |  |  |  |  |  |  |  |
|  |  | Update F0TG power on settings. |  |  |  |  |  |  |  |  | Fix that POST status error code will show up after set DETAILED_ERROR_MESSAGES as 0. |  |  |  |  |  |  |  |  |  |  |  |  |  |
|  |  |  |  |  |  |  |  |  |  |  | Add SW SSD and GPU to SMBIOS type9 list. |  |  |  |  |  |  |  |  |  |  |  |  |  |
| Issues fixed |  |  |  |  |  |  |  |  | Resolved etrack 405041-[F0TG EVT] The behavior for "Year" is not follow Help text. | Resolved etrack 406476-[F0TG EVT] Part Number info in Type 4 is not get from CPU PN. | Resolved eTrack 405688-[F0TG EVT] Wake on Lan function is not available. | eTrack number - 408368-[F0TG EVT] [ES14] It is not install OS in boot drive when all 9 E1.S are inserted. | Etrack#409637-[F0TG_EVT_PR CPU][ES6] BMC only assert SEL for device port when inject PCIe ''LCRC-TX'' error on NIC. | Etrack#409637-[F0TG_EVT_PR CPU][ES6] BMC only assert SEL for device port when inject PCIe ''LCRC-TX'' error on NIC. | Etrack#409900 [F0TG_EVT_PR CPU][ES6] Type 45 is not follow definition in SMBIOS SPEC. | Etrack#409843 [F0TG_EVT_PR CPU][ES6] System show memory error message on POST screen after insert bad DIMM in memory |  | Etrack#417050 [F0TG][DVT] SMBIOS type 9 IOX SSD that not install SSD shows Current Usage: In Use. | Etrack#418768[F0TG_DVT] BIOS setup display the ports number of PCIe SSD not match to PCIe Port Mapping. | Etrack#420604[F0TG_DVT_8 Retimer][DS2] It still got CPU1 PN info in Type 4 after removed CPU1. | Etrack#418789[F0TG_DVT_8 Retimer][DS2] BMC assert wrong SEL event in CPU 0 after inject MP1 Uncorrectable Error in Socket 1. | Etrack#424583[F0TG PVT] BIOS version in PVT should be named start from 3AXX. | Etrack#426402[F0TG PVT] [PS5] It got Space between "Part" and "Component" in SMBIOS Type2. | Etrack#427115[F0TG_PVT][PVT2 SWB][PS 7] No SEL after inject MP1 (SMU) correctable and uncorrectable error. |
|  |  |  |  |  |  |  |  |  | Resolved etrack 405040-[F0TG EVT] It failed to dump BIOS setting by SCE tool. | Resolved etrack 406434-[F0TG_EVT] It was hang at post code [95] after populating the GPU into system. | Resolved eTrack 407452-[F0TG_EVT]CPU0 DIMM sensor temp and watts value display "0" on BIOS FW F0TG1A09. | eTrack number - 408241-[F0TG][Customer issue] POST code is empty during system AC cycle. | Etrack#409160-[F0TG_EVT_PR CPU] When Inject PCIe Poisoned TLP RX error to NIC1, system will reset and SEL record MACHINE_CHK_ERR event. | Etrack#409160-[F0TG_EVT_PR CPU] When Inject PCIe Poisoned TLP RX error to NIC1, system will reset and SEL record MACHINE_CHK_ERR event. | Etrack#410925 [F0TG_EVT_PR CPU]AMISCE (v5.05.02.0003) pop some warning messages when import BIOS setting via SCELNX. |  |  | Etrack#408902 [F0TG_EVT_PR CPU] SEL record wrong ''ErrID2: 0x55, ErrID1: 0x50'' error ID when inject fatal error (MalformedTLP/ECRC) on E1.S by Keysight card. | Etrack#408978[F0TG_EVT_PR CPU][ES4] BMC IP address (from DHCP) would not change after setting to ''Static IP address'', but it saved in BIOS successfully. (SOL did not disconnect too.) | Etrack#420145[F0TG_DVT_8 Retimer][DS1] The Link Speed of root port for PCIE device was showed N/A by using AMDXIO via PCIePortStatusSBRStress(AMDXIO). | Etrack#418509[F0TG_DVT][Hi5#2] System stuck at POST after setting ''Above 4G Decoding'' to disabled. | Etrack#426219[F0TG PVT] [PS5] System print ''ERROR: Bad Date/Time'' during run uefi postcode after remove/plug in Battery. |  | Etrack#427137[F0TG_PVT][PVT2 SWB][PS 7] No SEL after inject MP5 correctable and uncorrectable error. |
|  |  |  |  |  |  |  |  |  | Resolved etrack 405028-[F0TG EVT] ROM Size in Type 0 mismatch with actual ROM Size. | Resolved etrack 406397-[F0TG EVT] System will hang and reboot after executed command '' lspci -xxxx'' under OS. | Resolved eTrack 407376-[F0TG EVT][ES2] The MB_CPU0_DIMM _PWR_W was showed 0.00 Watts via sensor-util mb with BIOS 1A09. | eTrack number - 407228-[F0EG][EVT][BIOS 1A07] SMBIOS type 1 Product Name not follow Quanta_OCP_Genoa_BIOS_Specification_0.2 define. | Etrack#409843-[F0TG_EVT_PR CPU][ES6] System show memory error message on POST screen after insert bad DIMM in memory slot. | Etrack#409843-[F0TG_EVT_PR CPU][ES6] System show memory error message on POST screen after insert bad DIMM in memory slot. | Etrack#410845 [F0TG_EVT_PR CPU]SEL record POST Failure Event ''Received invalid boot order request from BMC'' after reboot OS on BIOS F0TG1A13. |  |  |  | Etrack#418938[F0TG][DVT] POST Code not match with BIOS release note. | Etrack#419153[F0TG][DVT] Can't inject PCIe ACS Fatal Error to NIC by AMD RAS tool. | Etrack#419001[F0TG_DVT_8 Retimer][DS2] Inject WAFL Correcteable and Uncorrectable Error, SEL log ''Machine Check bank Number'' value are not meet BIOS SPEC defined. | Etrack#426133[F0TG PVT] [PS5] General Help of ''F1'' key at BIOS Setup Menu didn't show ''Tab'' Key function and not match BIOS spec defined. |  | Etrack#427246[F0TG_PVT][PVT2 SWB][PS 7] No OS event and SEL after injected 1st IOHUB Parity ECC Correctable Error. |
|  |  |  |  |  |  |  |  |  | Resolved etrack 405003-[F0TG_EVT] The capitalization of that word "Bmc" is different from the others in BIOS setting/Server Mgmt. | Resolved etrack 405426-[F0TG EVT] Version info in SMBIOS Type 3 cannot meet BIOS spec V0.2 defined. | Resolved eTrack 408003-[F0TG_EVT]BIOS POST code show error message after clear CMOS by jummper. | eTrack number - 408429-[F0TG][EVT] SEL not record '' POST Failure Event: System PXE boot fail'' log when PXE boot failed | Etrack#409402-[F0TG_EVT_PR CPU][2nd][B0 SWB][QS][ES2] The PCIe bus address via dmidecode was not match the bus address via lspci. | Etrack#409402-[F0TG_EVT_PR CPU][2nd][B0 SWB][QS][ES2] The PCIe bus address via dmidecode was not match the bus address via lspci. | Etrack#410862 [F0TG 1A13] [ES10] It can't change boot option setting after save& reset changed boot option order. (It always keep default Boot option ) |  |  |  | Etrack#420119[F0TG_DVT_8 Retimer][DS2] DIMM info does not match between OS and SEL after inject a Fatal uncorrectable error by APEI. | Etrack#419099[F0TG][DVT] Can't inject PCIe Poisoned TLP TX/RX error to NIC by AMD RAS tool. | Etrack#418996[F0TG_DVT_8 Retimer][DS2] System reset and BMC assert uncorrectable fatal SEL after inject WAFL corrected error. |  |  | Etrack#427423[F0TG_PVT][PVT2 SWB][PS 7] No SEL when inject 1st IOHUB Parity UCP Error. |
|  |  |  |  |  |  |  |  |  | Resolved etrack 404675-[F0TG EVT] BIOS package is not follow rule. | Resolved etrack 405594-[F0TG] It was showed ''Error: Access forbidden, only HTTPS connection is allowed.'' durning boot post. | Resolved eTrack 405883-[F0TG_EVT]BMC pop 'Unspecified error' message when get FLASH Info by ipmitool command. | eTrack number - 408891-[F0TG_EVT_PR CPU]CPU power value will over power limit value after set CPU Power capping by BMC apml_tool then run stressapptest. | Etrack#408978-[F0TG_EVT_PR CPU][ES4] BMC IP address (from DHCP) would not change after setting to ''Static IP address'', but it saved in BIOS successfully. (SOL did not disconnect too.) | Etrack#408978-[F0TG_EVT_PR CPU][ES4] BMC IP address (from DHCP) would not change after setting to ''Static IP address'', but it saved in BIOS successfully. (SOL did not disconnect too.) | Etrack#404675 [F0TG EVT] BIOS package is not follow rule. |  |  |  | Etrack#418710[F0TG][DVT] System does not have any SEL events and dmesg when Inject PCIe fatal error (MalformedTLP,ECRC) by Keysight. |  |  |  |  | Etrack#427425[F0TG_PVT][PVT2 SWB][PS 7] No SEL when inject 1st IOHUB Parity ECC Correctable Error. |
|  |  |  |  |  |  |  |  |  | Resolved etrack 405880-[F0TG_EVT] System show wrong DIMM location information when get DIMM location via IPMI command. | Resolved etrack 406059-[F0TG EVT] Not define POST Code for each type power cycle in BIOS release note. | Resolved eTrack 405445-[F0TG_EVT]Upgrade info does not shows CPU socket in SMBIOS Type 4. | eTrack number - 408870-[F0TG_EVT_PR CPU][ES4] BMC SEL did not rease after setting ''Erase SEL'' to ''Yes, On next reset'' in BIOS. | Etrack#408967-[F0TG_EVT_PR CPU][ES4] There are three dots in the enter field of ''Station IP Address'' can't be deleted when setting BMC static IP address in BIOS. | Etrack#408967-[F0TG_EVT_PR CPU][ES4] There are three dots in the enter field of ''Station IP Address'' can't be deleted when setting BMC static IP address in BIOS. |  |  |  |  | Etrack#408863[F0TG EVT] [ES14] SEL recorded ''ECC Error Disable Threshold'' event several times on the same DRAM. |  |  |  |  | Etrack#427437[F0TG_PVT][PVT2 SWB][PS 7] No SEL after inject WAFL Correctable Error. |
|  |  |  |  |  |  |  |  |  | Resolved etrack 405701-[F0TG EVT] SMBIOS type 2 - Location In Chassis shows SLOT1. | Resolved etrack 405969-[F0TG EVT] It got 2 Boot Option #1 if enter BIOS by user password. | Resolved eTrack 408462-[F0TG_EVT_PR CPU][ES4][BIOS F0TG1A09] The sequence of ''Designation: IOX-SSDx(PCIe x4)''  does not match physical slot number actually, E1.S are installed at SSD slot1,3,5 .etc, but it shows IOX-SSD0,2,4 .etc. |  | Etrack#410035-[F0TG_EVT_PR CPU][ES6] Microcode version not sync with BIOS release note. | Etrack#410035-[F0TG_EVT_PR CPU][ES6] Microcode version not sync with BIOS release note. |  |  |  |  | Etrack#407589[F0TG][EVT] SUT will hang after execute ping6 command cross network segment with DHCP env in EFI shell. |  |  |  |  | Etrack#426989[F0TG_PVT][PVT2 SWB][PS 7] No MEMORY_ECC_ERR SEL event after inject DRAM Explicit Userspace Error UCE-fatal Error. |
|  |  |  |  |  |  |  |  |  | Resolved etrack 405557-[F0TG_EVT] The "Current Restore on AC Power Loss" setting show "Unknown" on BIOS setup menu. | Resolved etrack 407077-[F0TG EVT][ES6] The Prompt Timeout will not display during POST screen. | Resolved eTrack 408458-[F0TG_EVT_PR CPU][ES4][BIOS F0TG1A09] The ''type'' of ''CPUx - OCP NICx'' would show ''   x16 PCI Express 4 x16'' in SMBIOS type 9, it should be ''x16 PCI Express 5 x16'' |  | Etrack#409892-[F0TG_EVT_PR CPU] BIOS release note ''ROM checksum'' and ''ROM MD5'' should modify to ''BIN checksum/MD5'' due to there are bin files in BIOS package. | Etrack#409892-[F0TG_EVT_PR CPU] BIOS release note ''ROM checksum'' and ''ROM MD5'' should modify to ''BIN checksum/MD5'' due to there are bin files in BIOS package. |  |  |  |  |  |  |  |  |  | Etrack#426856[F0TG_PVT][PVT2 SWB][PS 7] It lost SEL for DIMM B11 after inject DRAM Parity CE error. |
|  |  |  |  |  |  |  |  |  | Resolved etrack 404907-[F0TG_EVT] There are no POST code on SOL. | Resolved etrack 406023-[F0TG EVT] It shows ''./PreCheck.sh: No such file or directory'' message when execute ''./run_script'' with BIOS 1A08. | Resolved eTrack 407520-[F0TG][EVT] Please help to add ''dTPM is required and installed on MB to Power ON'' in BIOS release note. |  | Etrack#404675-[F0TG EVT] BIOS package is not follow rule. | Etrack#404675-[F0TG EVT] BIOS package is not follow rule. |  |  |  |  |  |  |  |  |  | Etrack#426623[F0TG_PVT][PVT2 SWB][PS 5] The format for PSP FW version in Type11 is not sync with the one in BIOS release note |
|  |  |  |  |  |  |  |  |  |  | Resolved etrack 405880-[F0TG_EVT] System show wrong DIMM location information when get DIMM location via IPMI command. | Resolved eTrack 407793-[F0TG][EVT] ABL version is inconsistent between BIOS setup and BIOS Release Note. |  | Etrack#410567-[F0TG_EVT_PR CPU][ES6] SMBIOS type 9 PCI Slot Information Data Bus Width shouldn't be 0. | Etrack#410567-[F0TG_EVT_PR CPU][ES6] SMBIOS type 9 PCI Slot Information Data Bus Width shouldn't be 0. |  |  |  |  |  |  |  |  |  | Etrack#426530[F0TG PVT] [PS7] No SEL after injected GMI CCD correctable error on linknumber 0. (It got HW error in OS event.) |
|  |  |  |  |  |  |  |  |  |  |  |  |  |  |  |  |  |  |  |  |  |  |  |  | Etrack#416765[F0TG][DVT] SMBIOS Type 7 L3 Cache size is not match to AMD SPEC. |
|  |  |  |  |  |  |  |  |  |  |  |  |  |  |  |  |  |  |  |  |  |  |  |  | Etrack#427457[F0TG_PVT][PVT2 SWB][PS 7] The SEL event is wrong and no PMIC SEL after inject PMIC error. |
